FILE_TYPE = MACRO_DRAWING;
SET COLOR_WIRE YELLOW;
SET COLOR_PROP ORANGE;
SET COLOR_DOT WHITE;
SET COLOR_ARC YELLOW;
SET COLOR_BODY GREEN;
SET COLOR_NOTE PURPLE;
SET PROP_DISPLAY VALUE;
SET PAGE_NUMBER P84;
FORCEADD UNIVERSAL_GND..1
(-1525 -475);
FORCEPROP 3 LASTPIN (-1525 -425) SIG_NAME GND\g
J 0
(-1515 -415);
DISPLAY 0.659574 (-1515 -415);
PAINT MONO (-1515 -415);
DISPLAY INVISIBLE (-1515 -415);
FORCEPROP 2 LAST CDS_LIB logical_power
J 0
(-1525 -475);
PAINT MONO (-1525 -475);
DISPLAY INVISIBLE (-1525 -475);
FORCEPROP 1 LAST HDL_POWER GND
J 1
(-1500 -550);
DISPLAY 0.872340 (-1500 -550);
PAINT GREEN (-1500 -550);
DISPLAY INVISIBLE (-1500 -550);
FORCEPROP 1 LAST PATH I1
J 0
(-1450 -475);
DISPLAY 0.872340 (-1450 -475);
PAINT AQUA (-1450 -475);
DISPLAY INVISIBLE (-1450 -475);
FORCEADD Q_RES..2
(-1525 -250);
FORCEPROP 1 LAST PART_NUMBER CS32322FB03
J 0
(-1485 -375);
DISPLAY 0.978723 (-1485 -375);
DISPLAY INVISIBLE (-1485 -375);
FORCEPROP 1 LAST VALUE 23.2K
J 0
(-1480 -175);
DISPLAY 0.978723 (-1480 -175);
FORCEPROP 1 LAST PACK_TYPE 0402LF
J 0
(-1485 -425);
DISPLAY 0.978723 (-1485 -425);
FORCEPROP 1 LAST WATTAGE 1/16W
J 0
(-1485 -275);
DISPLAY 0.978723 (-1485 -275);
FORCEPROP 1 LAST TOLERANCE 1%
J 0
(-1480 -225);
DISPLAY 0.978723 (-1480 -225);
FORCEPROP 1 LAST MATERIAL CHIP
J 0
(-1485 -325);
DISPLAY 0.978723 (-1485 -325);
FORCEPROP 1 LAST $LOCATION R28
J 0
(-1480 -125);
DISPLAY 0.978723 (-1480 -125);
FORCEPROP 1 LASTPIN (-1525 -150) $PN 1
J 0
(-1520 -188);
DISPLAY 0.787234 (-1520 -188);
FORCEPROP 1 LASTPIN (-1525 -350) $PN 2
J 0
(-1520 -340);
DISPLAY 0.787234 (-1520 -340);
FORCEPROP 2 LAST CDS_LIB pure_quanta
J 0
(-1525 -250);
PAINT MONO (-1525 -250);
DISPLAY INVISIBLE (-1525 -250);
FORCEPROP 2 LAST CDS_LOCATION R28
J 0
(-1475 -25);
DISPLAY 1.021277 (-1475 -25);
DISPLAY INVISIBLE (-1475 -25);
FORCEPROP 2 LAST $SEC 1
J 0
(-1475 -25);
DISPLAY 0.680851 (-1475 -25);
PAINT MONO (-1475 -25);
DISPLAY INVISIBLE (-1475 -25);
FORCEPROP 2 LAST CDS_SEC 1
J 0
(-1475 -25);
DISPLAY 1.021277 (-1475 -25);
DISPLAY INVISIBLE (-1475 -25);
FORCEPROP 1 LAST PATH I10
J 0
(-1475 -75);
DISPLAY 0.978723 (-1475 -75);
PAINT WHITE (-1475 -75);
DISPLAY INVISIBLE (-1475 -75);
FORCEADD TAP..1
(-100 3200);
FORCEPROP 3 LASTPIN (-150 3200) SIG_NAME M_B_CPU0_SA_DQ<17>
J 0
(-140 3210);
DISPLAY 0.659574 (-140 3210);
PAINT MONO (-140 3210);
DISPLAY INVISIBLE (-140 3210);
FORCEPROP 1 LASTPIN (-150 3200) BN 17
J 0
(-162 3208);
DISPLAY 0.680851 (-162 3208);
PAINT GREEN (-162 3208);
FORCEPROP 2 LAST CDS_LIB standard
J 0
(-100 3200);
PAINT MONO (-100 3200);
DISPLAY INVISIBLE (-100 3200);
FORCEPROP 1 LAST BODY_TYPE PLUMBING
J 0
(-100 3250);
DISPLAY 0.872340 (-100 3250);
PAINT GREEN (-100 3250);
DISPLAY INVISIBLE (-100 3250);
FORCEPROP 1 LAST HDL_TAP TRUE
J 0
(225 3075);
DISPLAY 0.872340 (225 3075);
DISPLAY INVISIBLE (225 3075);
FORCEPROP 1 LAST PATH I100
J 0
(-102 3200);
DISPLAY 0.872340 (-102 3200);
PAINT GREEN (-102 3200);
DISPLAY INVISIBLE (-102 3200);
FORCEADD TAP..1
(-100 3350);
FORCEPROP 3 LASTPIN (-150 3350) SIG_NAME M_B_CPU0_SA_DQ<20>
J 0
(-140 3360);
DISPLAY 0.659574 (-140 3360);
PAINT MONO (-140 3360);
DISPLAY INVISIBLE (-140 3360);
FORCEPROP 1 LASTPIN (-150 3350) BN 20
J 0
(-162 3358);
DISPLAY 0.680851 (-162 3358);
PAINT GREEN (-162 3358);
FORCEPROP 2 LAST CDS_LIB standard
J 0
(-100 3350);
PAINT MONO (-100 3350);
DISPLAY INVISIBLE (-100 3350);
FORCEPROP 1 LAST BODY_TYPE PLUMBING
J 0
(-100 3400);
DISPLAY 0.872340 (-100 3400);
PAINT GREEN (-100 3400);
DISPLAY INVISIBLE (-100 3400);
FORCEPROP 1 LAST HDL_TAP TRUE
J 0
(225 3225);
DISPLAY 0.872340 (225 3225);
DISPLAY INVISIBLE (225 3225);
FORCEPROP 1 LAST PATH I101
J 0
(-102 3350);
DISPLAY 0.872340 (-102 3350);
PAINT GREEN (-102 3350);
DISPLAY INVISIBLE (-102 3350);
FORCEADD TAP..1
(-100 3400);
FORCEPROP 3 LASTPIN (-150 3400) SIG_NAME M_B_CPU0_SA_DQ<21>
J 0
(-140 3410);
DISPLAY 0.659574 (-140 3410);
PAINT MONO (-140 3410);
DISPLAY INVISIBLE (-140 3410);
FORCEPROP 1 LASTPIN (-150 3400) BN 21
J 0
(-162 3408);
DISPLAY 0.680851 (-162 3408);
PAINT GREEN (-162 3408);
FORCEPROP 2 LAST CDS_LIB standard
J 0
(-100 3400);
PAINT MONO (-100 3400);
DISPLAY INVISIBLE (-100 3400);
FORCEPROP 1 LAST BODY_TYPE PLUMBING
J 0
(-100 3450);
DISPLAY 0.872340 (-100 3450);
PAINT GREEN (-100 3450);
DISPLAY INVISIBLE (-100 3450);
FORCEPROP 1 LAST HDL_TAP TRUE
J 0
(225 3275);
DISPLAY 0.872340 (225 3275);
DISPLAY INVISIBLE (225 3275);
FORCEPROP 1 LAST PATH I102
J 0
(-102 3400);
DISPLAY 0.872340 (-102 3400);
PAINT GREEN (-102 3400);
DISPLAY INVISIBLE (-102 3400);
FORCEADD TAP..1
(-100 3450);
FORCEPROP 3 LASTPIN (-150 3450) SIG_NAME M_B_CPU0_SA_DQ<22>
J 0
(-140 3460);
DISPLAY 0.659574 (-140 3460);
PAINT MONO (-140 3460);
DISPLAY INVISIBLE (-140 3460);
FORCEPROP 1 LASTPIN (-150 3450) BN 22
J 0
(-162 3458);
DISPLAY 0.680851 (-162 3458);
PAINT GREEN (-162 3458);
FORCEPROP 2 LAST CDS_LIB standard
J 0
(-100 3450);
DISPLAY INVISIBLE (-100 3450);
FORCEPROP 1 LAST BODY_TYPE PLUMBING
J 0
(-100 3500);
DISPLAY 0.872340 (-100 3500);
PAINT GREEN (-100 3500);
DISPLAY INVISIBLE (-100 3500);
FORCEPROP 1 LAST HDL_TAP TRUE
J 0
(225 3325);
DISPLAY 0.872340 (225 3325);
DISPLAY INVISIBLE (225 3325);
FORCEPROP 1 LAST PATH I103
J 0
(-102 3450);
DISPLAY 0.872340 (-102 3450);
PAINT GREEN (-102 3450);
DISPLAY INVISIBLE (-102 3450);
FORCEADD TAP..1
(-100 3500);
FORCEPROP 3 LASTPIN (-150 3500) SIG_NAME M_B_CPU0_SA_DQ<23>
J 0
(-140 3510);
DISPLAY 0.659574 (-140 3510);
PAINT MONO (-140 3510);
DISPLAY INVISIBLE (-140 3510);
FORCEPROP 1 LASTPIN (-150 3500) BN 23
J 0
(-162 3508);
DISPLAY 0.680851 (-162 3508);
PAINT GREEN (-162 3508);
FORCEPROP 2 LAST CDS_LIB standard
J 0
(-100 3500);
DISPLAY INVISIBLE (-100 3500);
FORCEPROP 1 LAST BODY_TYPE PLUMBING
J 0
(-100 3550);
DISPLAY 0.872340 (-100 3550);
PAINT GREEN (-100 3550);
DISPLAY INVISIBLE (-100 3550);
FORCEPROP 1 LAST HDL_TAP TRUE
J 0
(225 3375);
DISPLAY 0.872340 (225 3375);
DISPLAY INVISIBLE (225 3375);
FORCEPROP 1 LAST PATH I104
J 0
(-102 3500);
DISPLAY 0.872340 (-102 3500);
PAINT GREEN (-102 3500);
DISPLAY INVISIBLE (-102 3500);
FORCEADD TAP..1
(-100 3550);
FORCEPROP 3 LASTPIN (-150 3550) SIG_NAME M_B_CPU0_SA_DQ<24>
J 0
(-140 3560);
DISPLAY 0.659574 (-140 3560);
PAINT MONO (-140 3560);
DISPLAY INVISIBLE (-140 3560);
FORCEPROP 1 LASTPIN (-150 3550) BN 24
J 0
(-162 3558);
DISPLAY 0.680851 (-162 3558);
PAINT GREEN (-162 3558);
FORCEPROP 2 LAST CDS_LIB standard
J 0
(-100 3550);
DISPLAY INVISIBLE (-100 3550);
FORCEPROP 1 LAST BODY_TYPE PLUMBING
J 0
(-100 3600);
DISPLAY 0.872340 (-100 3600);
PAINT GREEN (-100 3600);
DISPLAY INVISIBLE (-100 3600);
FORCEPROP 1 LAST HDL_TAP TRUE
J 0
(225 3425);
DISPLAY 0.872340 (225 3425);
DISPLAY INVISIBLE (225 3425);
FORCEPROP 1 LAST PATH I105
J 0
(-102 3550);
DISPLAY 0.872340 (-102 3550);
PAINT GREEN (-102 3550);
DISPLAY INVISIBLE (-102 3550);
FORCEADD TAP..1
(-100 3600);
FORCEPROP 3 LASTPIN (-150 3600) SIG_NAME M_B_CPU0_SA_DQ<25>
J 0
(-140 3610);
DISPLAY 0.659574 (-140 3610);
PAINT MONO (-140 3610);
DISPLAY INVISIBLE (-140 3610);
FORCEPROP 1 LASTPIN (-150 3600) BN 25
J 0
(-162 3608);
DISPLAY 0.680851 (-162 3608);
PAINT GREEN (-162 3608);
FORCEPROP 2 LAST CDS_LIB standard
J 0
(-100 3600);
DISPLAY INVISIBLE (-100 3600);
FORCEPROP 1 LAST BODY_TYPE PLUMBING
J 0
(-100 3650);
DISPLAY 0.872340 (-100 3650);
PAINT GREEN (-100 3650);
DISPLAY INVISIBLE (-100 3650);
FORCEPROP 1 LAST HDL_TAP TRUE
J 0
(225 3475);
DISPLAY 0.872340 (225 3475);
DISPLAY INVISIBLE (225 3475);
FORCEPROP 1 LAST PATH I106
J 0
(-102 3600);
DISPLAY 0.872340 (-102 3600);
PAINT GREEN (-102 3600);
DISPLAY INVISIBLE (-102 3600);
FORCEADD TAP..1
(-100 3650);
FORCEPROP 3 LASTPIN (-150 3650) SIG_NAME M_B_CPU0_SA_DQ<26>
J 0
(-140 3660);
DISPLAY 0.659574 (-140 3660);
PAINT MONO (-140 3660);
DISPLAY INVISIBLE (-140 3660);
FORCEPROP 1 LASTPIN (-150 3650) BN 26
J 0
(-162 3658);
DISPLAY 0.680851 (-162 3658);
PAINT GREEN (-162 3658);
FORCEPROP 2 LAST CDS_LIB standard
J 0
(-100 3650);
DISPLAY INVISIBLE (-100 3650);
FORCEPROP 1 LAST BODY_TYPE PLUMBING
J 0
(-100 3700);
DISPLAY 0.872340 (-100 3700);
PAINT GREEN (-100 3700);
DISPLAY INVISIBLE (-100 3700);
FORCEPROP 1 LAST HDL_TAP TRUE
J 0
(225 3525);
DISPLAY 0.872340 (225 3525);
DISPLAY INVISIBLE (225 3525);
FORCEPROP 1 LAST PATH I107
J 0
(-102 3650);
DISPLAY 0.872340 (-102 3650);
PAINT GREEN (-102 3650);
DISPLAY INVISIBLE (-102 3650);
FORCEADD OFFPAGE..1
(-2675 3925);
FORCEPROP 2 LAST $XR1 85 
J 0
(-2986 3925);
DISPLAY 0.638298 (-2986 3925);
PAINT MONO (-2986 3925);
FORCEPROP 2 LAST $XR0 21 
J 0
(-2896 3925);
DISPLAY 0.638298 (-2896 3925);
PAINT MONO (-2896 3925);
FORCEPROP 2 LAST CDS_LIB standard
J 0
(-2675 3925);
PAINT MONO (-2675 3925);
DISPLAY INVISIBLE (-2675 3925);
FORCEPROP 1 LAST OFFPAGE TRUE
J 0
(-2350 3800);
DISPLAY 0.872340 (-2350 3800);
DISPLAY INVISIBLE (-2350 3800);
FORCEPROP 1 LAST COMMENT_BODY TRUE
J 0
(-2550 3825);
DISPLAY 0.872340 (-2550 3825);
PAINT GREEN (-2550 3825);
DISPLAY INVISIBLE (-2550 3825);
FORCEPROP 2 LAST PATH I108
J 0
(-2625 4000);
DISPLAY 1.021277 (-2625 4000);
DISPLAY INVISIBLE (-2625 4000);
FORCEADD TAP..1
R 2
(-1750 3700);
FORCEPROP 3 LASTPIN (-1700 3700) SIG_NAME M_B_CPU0_SA_CA<2>
J 0
(-1690 3710);
DISPLAY 0.659574 (-1690 3710);
PAINT MONO (-1690 3710);
DISPLAY INVISIBLE (-1690 3710);
FORCEPROP 1 LASTPIN (-1700 3700) BN 2
J 2
(-1688 3708);
DISPLAY 0.680851 (-1688 3708);
PAINT GREEN (-1688 3708);
FORCEPROP 2 LAST CDS_LIB standard
J 0
(-1750 3700);
DISPLAY INVISIBLE (-1750 3700);
FORCEPROP 1 LAST BODY_TYPE PLUMBING
J 2
(-1750 3750);
DISPLAY 0.872340 (-1750 3750);
PAINT GREEN (-1750 3750);
DISPLAY INVISIBLE (-1750 3750);
FORCEPROP 1 LAST HDL_TAP TRUE
J 2
(-2075 3575);
DISPLAY 0.872340 (-2075 3575);
DISPLAY INVISIBLE (-2075 3575);
FORCEPROP 1 LAST PATH I109
J 2
(-1748 3700);
DISPLAY 0.872340 (-1748 3700);
PAINT GREEN (-1748 3700);
DISPLAY INVISIBLE (-1748 3700);
FORCEADD TAP..1
R 2
(-1750 3750);
FORCEPROP 3 LASTPIN (-1700 3750) SIG_NAME M_B_CPU0_SA_CA<3>
J 0
(-1690 3760);
DISPLAY 0.659574 (-1690 3760);
PAINT MONO (-1690 3760);
DISPLAY INVISIBLE (-1690 3760);
FORCEPROP 1 LASTPIN (-1700 3750) BN 3
J 2
(-1688 3758);
DISPLAY 0.680851 (-1688 3758);
PAINT GREEN (-1688 3758);
FORCEPROP 2 LAST CDS_LIB standard
J 0
(-1750 3750);
DISPLAY INVISIBLE (-1750 3750);
FORCEPROP 1 LAST BODY_TYPE PLUMBING
J 2
(-1750 3800);
DISPLAY 0.872340 (-1750 3800);
PAINT GREEN (-1750 3800);
DISPLAY INVISIBLE (-1750 3800);
FORCEPROP 1 LAST HDL_TAP TRUE
J 2
(-2075 3625);
DISPLAY 0.872340 (-2075 3625);
DISPLAY INVISIBLE (-2075 3625);
FORCEPROP 1 LAST PATH I110
J 2
(-1748 3750);
DISPLAY 0.872340 (-1748 3750);
PAINT GREEN (-1748 3750);
DISPLAY INVISIBLE (-1748 3750);
FORCEADD TAP..1
R 2
(-1750 3800);
FORCEPROP 3 LASTPIN (-1700 3800) SIG_NAME M_B_CPU0_SA_CA<4>
J 0
(-1690 3810);
DISPLAY 0.659574 (-1690 3810);
PAINT MONO (-1690 3810);
DISPLAY INVISIBLE (-1690 3810);
FORCEPROP 1 LASTPIN (-1700 3800) BN 4
J 2
(-1688 3808);
DISPLAY 0.680851 (-1688 3808);
PAINT GREEN (-1688 3808);
FORCEPROP 2 LAST CDS_LIB standard
J 0
(-1750 3800);
DISPLAY INVISIBLE (-1750 3800);
FORCEPROP 1 LAST BODY_TYPE PLUMBING
J 2
(-1750 3850);
DISPLAY 0.872340 (-1750 3850);
PAINT GREEN (-1750 3850);
DISPLAY INVISIBLE (-1750 3850);
FORCEPROP 1 LAST HDL_TAP TRUE
J 2
(-2075 3675);
DISPLAY 0.872340 (-2075 3675);
DISPLAY INVISIBLE (-2075 3675);
FORCEPROP 1 LAST PATH I111
J 2
(-1748 3800);
DISPLAY 0.872340 (-1748 3800);
PAINT GREEN (-1748 3800);
DISPLAY INVISIBLE (-1748 3800);
FORCEADD TAP..1
R 2
(-1750 3900);
FORCEPROP 3 LASTPIN (-1700 3900) SIG_NAME M_B_CPU0_SA_CA<6>
J 0
(-1690 3910);
DISPLAY 0.659574 (-1690 3910);
PAINT MONO (-1690 3910);
DISPLAY INVISIBLE (-1690 3910);
FORCEPROP 1 LASTPIN (-1700 3900) BN 6
J 2
(-1688 3908);
DISPLAY 0.680851 (-1688 3908);
PAINT GREEN (-1688 3908);
FORCEPROP 2 LAST CDS_LIB standard
J 0
(-1750 3900);
DISPLAY INVISIBLE (-1750 3900);
FORCEPROP 1 LAST BODY_TYPE PLUMBING
J 2
(-1750 3950);
DISPLAY 0.872340 (-1750 3950);
PAINT GREEN (-1750 3950);
DISPLAY INVISIBLE (-1750 3950);
FORCEPROP 1 LAST HDL_TAP TRUE
J 2
(-2075 3775);
DISPLAY 0.872340 (-2075 3775);
DISPLAY INVISIBLE (-2075 3775);
FORCEPROP 1 LAST PATH I112
J 2
(-1748 3900);
DISPLAY 0.872340 (-1748 3900);
PAINT GREEN (-1748 3900);
DISPLAY INVISIBLE (-1748 3900);
FORCEADD TAP..1
R 2
(-1750 3850);
FORCEPROP 3 LASTPIN (-1700 3850) SIG_NAME M_B_CPU0_SA_CA<5>
J 0
(-1690 3860);
DISPLAY 0.659574 (-1690 3860);
PAINT MONO (-1690 3860);
DISPLAY INVISIBLE (-1690 3860);
FORCEPROP 1 LASTPIN (-1700 3850) BN 5
J 2
(-1688 3858);
DISPLAY 0.680851 (-1688 3858);
PAINT GREEN (-1688 3858);
FORCEPROP 2 LAST CDS_LIB standard
J 0
(-1750 3850);
DISPLAY INVISIBLE (-1750 3850);
FORCEPROP 1 LAST BODY_TYPE PLUMBING
J 2
(-1750 3900);
DISPLAY 0.872340 (-1750 3900);
PAINT GREEN (-1750 3900);
DISPLAY INVISIBLE (-1750 3900);
FORCEPROP 1 LAST HDL_TAP TRUE
J 2
(-2075 3725);
DISPLAY 0.872340 (-2075 3725);
DISPLAY INVISIBLE (-2075 3725);
FORCEPROP 1 LAST PATH I113
J 2
(-1748 3850);
DISPLAY 0.872340 (-1748 3850);
PAINT GREEN (-1748 3850);
DISPLAY INVISIBLE (-1748 3850);
FORCEADD TAP..1
(-100 3800);
FORCEPROP 3 LASTPIN (-150 3800) SIG_NAME M_B_CPU0_SA_DQ<29>
J 0
(-140 3810);
DISPLAY 0.659574 (-140 3810);
PAINT MONO (-140 3810);
DISPLAY INVISIBLE (-140 3810);
FORCEPROP 1 LASTPIN (-150 3800) BN 29
J 0
(-162 3808);
DISPLAY 0.680851 (-162 3808);
PAINT GREEN (-162 3808);
FORCEPROP 2 LAST CDS_LIB standard
J 0
(-100 3800);
DISPLAY INVISIBLE (-100 3800);
FORCEPROP 1 LAST BODY_TYPE PLUMBING
J 0
(-100 3850);
DISPLAY 0.872340 (-100 3850);
PAINT GREEN (-100 3850);
DISPLAY INVISIBLE (-100 3850);
FORCEPROP 1 LAST HDL_TAP TRUE
J 0
(225 3675);
DISPLAY 0.872340 (225 3675);
DISPLAY INVISIBLE (225 3675);
FORCEPROP 1 LAST PATH I114
J 0
(-102 3800);
DISPLAY 0.872340 (-102 3800);
PAINT GREEN (-102 3800);
DISPLAY INVISIBLE (-102 3800);
FORCEADD TAP..1
(-100 3700);
FORCEPROP 3 LASTPIN (-150 3700) SIG_NAME M_B_CPU0_SA_DQ<27>
J 0
(-140 3710);
DISPLAY 0.659574 (-140 3710);
PAINT MONO (-140 3710);
DISPLAY INVISIBLE (-140 3710);
FORCEPROP 1 LASTPIN (-150 3700) BN 27
J 0
(-162 3708);
DISPLAY 0.680851 (-162 3708);
PAINT GREEN (-162 3708);
FORCEPROP 2 LAST CDS_LIB standard
J 0
(-100 3700);
DISPLAY INVISIBLE (-100 3700);
FORCEPROP 1 LAST BODY_TYPE PLUMBING
J 0
(-100 3750);
DISPLAY 0.872340 (-100 3750);
PAINT GREEN (-100 3750);
DISPLAY INVISIBLE (-100 3750);
FORCEPROP 1 LAST HDL_TAP TRUE
J 0
(225 3575);
DISPLAY 0.872340 (225 3575);
DISPLAY INVISIBLE (225 3575);
FORCEPROP 1 LAST PATH I115
J 0
(-102 3700);
DISPLAY 0.872340 (-102 3700);
PAINT GREEN (-102 3700);
DISPLAY INVISIBLE (-102 3700);
FORCEADD TAP..1
(-100 3750);
FORCEPROP 3 LASTPIN (-150 3750) SIG_NAME M_B_CPU0_SA_DQ<28>
J 0
(-140 3760);
DISPLAY 0.659574 (-140 3760);
PAINT MONO (-140 3760);
DISPLAY INVISIBLE (-140 3760);
FORCEPROP 1 LASTPIN (-150 3750) BN 28
J 0
(-162 3758);
DISPLAY 0.680851 (-162 3758);
PAINT GREEN (-162 3758);
FORCEPROP 2 LAST CDS_LIB standard
J 0
(-100 3750);
DISPLAY INVISIBLE (-100 3750);
FORCEPROP 1 LAST BODY_TYPE PLUMBING
J 0
(-100 3800);
DISPLAY 0.872340 (-100 3800);
PAINT GREEN (-100 3800);
DISPLAY INVISIBLE (-100 3800);
FORCEPROP 1 LAST HDL_TAP TRUE
J 0
(225 3625);
DISPLAY 0.872340 (225 3625);
DISPLAY INVISIBLE (225 3625);
FORCEPROP 1 LAST PATH I116
J 0
(-102 3750);
DISPLAY 0.872340 (-102 3750);
PAINT GREEN (-102 3750);
DISPLAY INVISIBLE (-102 3750);
FORCEADD TAP..1
(-100 3850);
FORCEPROP 3 LASTPIN (-150 3850) SIG_NAME M_B_CPU0_SA_DQ<30>
J 0
(-140 3860);
DISPLAY 0.659574 (-140 3860);
PAINT MONO (-140 3860);
DISPLAY INVISIBLE (-140 3860);
FORCEPROP 1 LASTPIN (-150 3850) BN 30
J 0
(-162 3858);
DISPLAY 0.680851 (-162 3858);
PAINT GREEN (-162 3858);
FORCEPROP 2 LAST CDS_LIB standard
J 0
(-100 3850);
DISPLAY INVISIBLE (-100 3850);
FORCEPROP 1 LAST BODY_TYPE PLUMBING
J 0
(-100 3900);
DISPLAY 0.872340 (-100 3900);
PAINT GREEN (-100 3900);
DISPLAY INVISIBLE (-100 3900);
FORCEPROP 1 LAST HDL_TAP TRUE
J 0
(225 3725);
DISPLAY 0.872340 (225 3725);
DISPLAY INVISIBLE (225 3725);
FORCEPROP 1 LAST PATH I117
J 0
(-102 3850);
DISPLAY 0.872340 (-102 3850);
PAINT GREEN (-102 3850);
DISPLAY INVISIBLE (-102 3850);
FORCEADD TAP..1
(-100 3900);
FORCEPROP 3 LASTPIN (-150 3900) SIG_NAME M_B_CPU0_SA_DQ<31>
J 0
(-140 3910);
DISPLAY 0.659574 (-140 3910);
PAINT MONO (-140 3910);
DISPLAY INVISIBLE (-140 3910);
FORCEPROP 1 LASTPIN (-150 3900) BN 31
J 0
(-162 3908);
DISPLAY 0.680851 (-162 3908);
PAINT GREEN (-162 3908);
FORCEPROP 2 LAST CDS_LIB standard
J 0
(-100 3900);
DISPLAY INVISIBLE (-100 3900);
FORCEPROP 1 LAST BODY_TYPE PLUMBING
J 0
(-100 3950);
DISPLAY 0.872340 (-100 3950);
PAINT GREEN (-100 3950);
DISPLAY INVISIBLE (-100 3950);
FORCEPROP 1 LAST HDL_TAP TRUE
J 0
(225 3775);
DISPLAY 0.872340 (225 3775);
DISPLAY INVISIBLE (225 3775);
FORCEPROP 1 LAST PATH I118
J 0
(-102 3900);
DISPLAY 0.872340 (-102 3900);
PAINT GREEN (-102 3900);
DISPLAY INVISIBLE (-102 3900);
FORCEADD VCC_CORE..1
(1625 350);
FORCEPROP 3 LASTPIN (1625 300) SIG_NAME P3V3_AUX\g
J 0
(1635 310);
DISPLAY 0.659574 (1635 310);
PAINT MONO (1635 310);
DISPLAY INVISIBLE (1635 310);
FORCEPROP 1 LAST HDL_POWER P3V3_AUX
J 1
(1625 400);
DISPLAY 1.148936 (1625 400);
PAINT GREEN (1625 400);
FORCEPROP 2 LAST CDS_LIB logical_power
J 0
(1625 350);
PAINT MONO (1625 350);
DISPLAY INVISIBLE (1625 350);
FORCEPROP 1 LAST PATH I119
J 0
(1675 375);
DISPLAY 0.872340 (1675 375);
PAINT AQUA (1675 375);
DISPLAY INVISIBLE (1675 375);
FORCEADD OFFPAGE..3
R 2
(-2675 2075);
FORCEPROP 2 LAST $XR1 85 
J 0
(-3014 2075);
DISPLAY 0.638298 (-3014 2075);
PAINT MONO (-3014 2075);
FORCEPROP 2 LAST $XR0 21 
J 0
(-2924 2075);
DISPLAY 0.638298 (-2924 2075);
PAINT MONO (-2924 2075);
FORCEPROP 2 LAST CDS_LIB standard
J 0
(-2675 2075);
PAINT MONO (-2675 2075);
DISPLAY INVISIBLE (-2675 2075);
FORCEPROP 1 LAST OFFPAGE TRUE
J 2
(-3000 1950);
DISPLAY 0.872340 (-3000 1950);
DISPLAY INVISIBLE (-3000 1950);
FORCEPROP 1 LAST COMMENT_BODY TRUE
J 2
(-2625 1975);
DISPLAY 0.872340 (-2625 1975);
PAINT GREEN (-2625 1975);
DISPLAY INVISIBLE (-2625 1975);
FORCEPROP 2 LAST PATH I12
J 0
(-2625 2150);
DISPLAY 1.021277 (-2625 2150);
DISPLAY INVISIBLE (-2625 2150);
FORCEADD UNIVERSAL_GND..1
(1625 -350);
FORCEPROP 3 LASTPIN (1625 -300) SIG_NAME GND\g
J 0
(1635 -290);
DISPLAY 0.659574 (1635 -290);
PAINT MONO (1635 -290);
DISPLAY INVISIBLE (1635 -290);
FORCEPROP 2 LAST CDS_LIB logical_power
J 0
(1625 -350);
PAINT MONO (1625 -350);
DISPLAY INVISIBLE (1625 -350);
FORCEPROP 1 LAST HDL_POWER GND
J 1
(1650 -425);
DISPLAY 0.872340 (1650 -425);
PAINT GREEN (1650 -425);
DISPLAY INVISIBLE (1650 -425);
FORCEPROP 1 LAST PATH I120
J 0
(1700 -350);
DISPLAY 0.872340 (1700 -350);
PAINT AQUA (1700 -350);
DISPLAY INVISIBLE (1700 -350);
FORCEADD Q_CAP..1
(1625 25);
FORCEPROP 1 LAST PART_NUMBER CH5221MEB00
J 0
(1675 -125);
DISPLAY 0.978723 (1675 -125);
DISPLAY INVISIBLE (1675 -125);
FORCEPROP 1 LAST VOLTAGE 6.3V
J 0
(1675 25);
DISPLAY 0.978723 (1675 25);
FORCEPROP 1 LAST VALUE 2.2UF
J 0
(1675 75);
DISPLAY 0.978723 (1675 75);
FORCEPROP 1 LAST TOLERANCE 20%
J 0
(1675 -25);
DISPLAY 0.978723 (1675 -25);
FORCEPROP 1 LAST MATERIAL X6S
J 0
(1675 -75);
DISPLAY 0.978723 (1675 -75);
FORCEPROP 1 LAST PACK_TYPE C0402
J 0
(1675 -175);
DISPLAY 0.978723 (1675 -175);
FORCEPROP 1 LAST $LOCATION C8
J 0
(1675 125);
DISPLAY 0.978723 (1675 125);
FORCEPROP 1 LASTPIN (1625 125) $PN 1
J 0
(1635 105);
DISPLAY 0.787234 (1635 105);
FORCEPROP 1 LASTPIN (1625 -75) $PN 2
J 0
(1635 -95);
DISPLAY 0.787234 (1635 -95);
FORCEPROP 2 LAST CDS_LIB pure_quanta
J 0
(1625 25);
PAINT MONO (1625 25);
DISPLAY INVISIBLE (1625 25);
FORCEPROP 2 LAST CDS_LOCATION C8
J 0
(1675 225);
DISPLAY 1.021277 (1675 225);
DISPLAY INVISIBLE (1675 225);
FORCEPROP 2 LAST $SEC 1
J 0
(1675 225);
DISPLAY 0.680851 (1675 225);
PAINT MONO (1675 225);
DISPLAY INVISIBLE (1675 225);
FORCEPROP 2 LAST CDS_SEC 1
J 0
(1675 225);
DISPLAY 1.021277 (1675 225);
DISPLAY INVISIBLE (1675 225);
FORCEPROP 1 LAST PATH I121
J 0
(1675 175);
DISPLAY 0.978723 (1675 175);
PAINT WHITE (1675 175);
DISPLAY INVISIBLE (1675 175);
FORCEADD Q_CAP..1
(2625 25);
FORCEPROP 1 LAST PART_NUMBER CH6103KEA00
J 0
(2675 -125);
DISPLAY 0.978723 (2675 -125);
DISPLAY INVISIBLE (2675 -125);
FORCEPROP 1 LAST VOLTAGE 16V
J 0
(2675 25);
DISPLAY 0.978723 (2675 25);
FORCEPROP 1 LAST TOLERANCE 10%
J 0
(2675 -25);
DISPLAY 0.978723 (2675 -25);
FORCEPROP 1 LAST PACK_TYPE C0805
J 0
(2675 -175);
DISPLAY 0.978723 (2675 -175);
FORCEPROP 1 LAST VALUE 10UF
J 0
(2675 75);
DISPLAY 0.978723 (2675 75);
FORCEPROP 1 LAST MATERIAL X6S
J 0
(2675 -75);
DISPLAY 0.978723 (2675 -75);
FORCEPROP 1 LAST $LOCATION C9
J 0
(2675 125);
DISPLAY 0.978723 (2675 125);
FORCEPROP 1 LASTPIN (2625 125) $PN 1
J 0
(2635 105);
DISPLAY 0.787234 (2635 105);
FORCEPROP 1 LASTPIN (2625 -75) $PN 2
J 0
(2635 -95);
DISPLAY 0.787234 (2635 -95);
FORCEPROP 2 LAST CDS_LIB pure_quanta
J 0
(2625 25);
PAINT MONO (2625 25);
DISPLAY INVISIBLE (2625 25);
FORCEPROP 2 LAST CDS_LOCATION C9
J 0
(2675 225);
DISPLAY 1.021277 (2675 225);
DISPLAY INVISIBLE (2675 225);
FORCEPROP 2 LAST $SEC 1
J 0
(2675 225);
DISPLAY 0.680851 (2675 225);
PAINT MONO (2675 225);
DISPLAY INVISIBLE (2675 225);
FORCEPROP 2 LAST CDS_SEC 1
J 0
(2675 225);
DISPLAY 1.021277 (2675 225);
DISPLAY INVISIBLE (2675 225);
FORCEPROP 1 LAST PATH I122
J 0
(2675 175);
DISPLAY 0.978723 (2675 175);
PAINT WHITE (2675 175);
DISPLAY INVISIBLE (2675 175);
FORCEADD VCC_CORE..1
(2625 350);
FORCEPROP 3 LASTPIN (2625 300) SIG_NAME P12V_S3_AUX_CPU0_NVDIMM\g
J 0
(2635 310);
DISPLAY 0.659574 (2635 310);
PAINT MONO (2635 310);
DISPLAY INVISIBLE (2635 310);
FORCEPROP 1 LAST HDL_POWER P12V_S3_AUX_CPU0_NVDIMM
J 1
(2625 400);
DISPLAY 1.148936 (2625 400);
PAINT GREEN (2625 400);
FORCEPROP 2 LAST CDS_LIB logical_power
J 0
(2625 350);
PAINT MONO (2625 350);
DISPLAY INVISIBLE (2625 350);
FORCEPROP 1 LAST PATH I123
J 0
(2675 375);
DISPLAY 0.872340 (2675 375);
PAINT AQUA (2675 375);
DISPLAY INVISIBLE (2675 375);
FORCEADD OFFPAGE..3
(725 2275);
FORCEPROP 2 LAST $XR1 85 
J 0
(1029 2275);
DISPLAY 0.638298 (1029 2275);
PAINT MONO (1029 2275);
FORCEPROP 2 LAST $XR0 21 
J 0
(939 2275);
DISPLAY 0.638298 (939 2275);
PAINT MONO (939 2275);
FORCEPROP 2 LAST CDS_LIB standard
J 2
(725 2275);
DISPLAY INVISIBLE (725 2275);
FORCEPROP 1 LAST OFFPAGE TRUE
J 0
(1050 2150);
DISPLAY 0.872340 (1050 2150);
DISPLAY INVISIBLE (1050 2150);
FORCEPROP 1 LAST COMMENT_BODY TRUE
J 0
(675 2175);
DISPLAY 0.872340 (675 2175);
PAINT GREEN (675 2175);
DISPLAY INVISIBLE (675 2175);
FORCEPROP 2 LAST PATH I124
J 0
(925 2350);
DISPLAY 1.021277 (925 2350);
DISPLAY INVISIBLE (925 2350);
FORCEADD TAP..1
(2625 1950);
FORCEPROP 3 LASTPIN (2575 1950) SIG_NAME M_B_CPU0_SB_DQS_DP<0>
J 0
(2585 1960);
DISPLAY 0.659574 (2585 1960);
PAINT MONO (2585 1960);
DISPLAY INVISIBLE (2585 1960);
FORCEPROP 1 LASTPIN (2575 1950) BN 0
J 0
(2563 1958);
DISPLAY 0.680851 (2563 1958);
PAINT GREEN (2563 1958);
FORCEPROP 2 LAST CDS_LIB standard
J 0
(2625 1950);
PAINT MONO (2625 1950);
DISPLAY INVISIBLE (2625 1950);
FORCEPROP 1 LAST BODY_TYPE PLUMBING
J 0
(2625 2000);
DISPLAY 0.872340 (2625 2000);
PAINT GREEN (2625 2000);
DISPLAY INVISIBLE (2625 2000);
FORCEPROP 1 LAST HDL_TAP TRUE
J 0
(2950 1825);
DISPLAY 0.872340 (2950 1825);
DISPLAY INVISIBLE (2950 1825);
FORCEPROP 1 LAST PATH I126
J 0
(2623 1950);
DISPLAY 0.872340 (2623 1950);
PAINT GREEN (2623 1950);
DISPLAY INVISIBLE (2623 1950);
FORCEADD TAP..1
(2625 2150);
FORCEPROP 3 LASTPIN (2575 2150) SIG_NAME M_B_CPU0_SB_DQS_DP<2>
J 0
(2585 2160);
DISPLAY 0.659574 (2585 2160);
PAINT MONO (2585 2160);
DISPLAY INVISIBLE (2585 2160);
FORCEPROP 1 LASTPIN (2575 2150) BN 2
J 0
(2563 2158);
DISPLAY 0.680851 (2563 2158);
PAINT GREEN (2563 2158);
FORCEPROP 2 LAST CDS_LIB standard
J 0
(2625 2150);
DISPLAY INVISIBLE (2625 2150);
FORCEPROP 1 LAST BODY_TYPE PLUMBING
J 0
(2625 2200);
DISPLAY 0.872340 (2625 2200);
PAINT GREEN (2625 2200);
DISPLAY INVISIBLE (2625 2200);
FORCEPROP 1 LAST HDL_TAP TRUE
J 0
(2950 2025);
DISPLAY 0.872340 (2950 2025);
DISPLAY INVISIBLE (2950 2025);
FORCEPROP 1 LAST PATH I127
J 0
(2623 2150);
DISPLAY 0.872340 (2623 2150);
PAINT GREEN (2623 2150);
DISPLAY INVISIBLE (2623 2150);
FORCEADD TAP..1
(2625 2050);
FORCEPROP 3 LASTPIN (2575 2050) SIG_NAME M_B_CPU0_SB_DQS_DP<1>
J 0
(2585 2060);
DISPLAY 0.659574 (2585 2060);
PAINT MONO (2585 2060);
DISPLAY INVISIBLE (2585 2060);
FORCEPROP 1 LASTPIN (2575 2050) BN 1
J 0
(2563 2058);
DISPLAY 0.680851 (2563 2058);
PAINT GREEN (2563 2058);
FORCEPROP 2 LAST CDS_LIB standard
J 0
(2625 2050);
DISPLAY INVISIBLE (2625 2050);
FORCEPROP 1 LAST BODY_TYPE PLUMBING
J 0
(2625 2100);
DISPLAY 0.872340 (2625 2100);
PAINT GREEN (2625 2100);
DISPLAY INVISIBLE (2625 2100);
FORCEPROP 1 LAST HDL_TAP TRUE
J 0
(2950 1925);
DISPLAY 0.872340 (2950 1925);
DISPLAY INVISIBLE (2950 1925);
FORCEPROP 1 LAST PATH I128
J 0
(2623 2050);
DISPLAY 0.872340 (2623 2050);
PAINT GREEN (2623 2050);
DISPLAY INVISIBLE (2623 2050);
FORCEADD TAP..1
(2625 2250);
FORCEPROP 3 LASTPIN (2575 2250) SIG_NAME M_B_CPU0_SB_DQS_DP<3>
J 0
(2585 2260);
DISPLAY 0.659574 (2585 2260);
PAINT MONO (2585 2260);
DISPLAY INVISIBLE (2585 2260);
FORCEPROP 1 LASTPIN (2575 2250) BN 3
J 0
(2563 2258);
DISPLAY 0.680851 (2563 2258);
PAINT GREEN (2563 2258);
FORCEPROP 2 LAST CDS_LIB standard
J 0
(2625 2250);
PAINT MONO (2625 2250);
DISPLAY INVISIBLE (2625 2250);
FORCEPROP 1 LAST BODY_TYPE PLUMBING
J 0
(2625 2300);
DISPLAY 0.872340 (2625 2300);
PAINT GREEN (2625 2300);
DISPLAY INVISIBLE (2625 2300);
FORCEPROP 1 LAST HDL_TAP TRUE
J 0
(2950 2125);
DISPLAY 0.872340 (2950 2125);
DISPLAY INVISIBLE (2950 2125);
FORCEPROP 1 LAST PATH I129
J 0
(2623 2250);
DISPLAY 0.872340 (2623 2250);
PAINT GREEN (2623 2250);
DISPLAY INVISIBLE (2623 2250);
FORCEADD VCC_CORE..1
(-2575 1775);
FORCEPROP 3 LASTPIN (-2575 1725) SIG_NAME P3V3_AUX\g
J 0
(-2565 1735);
DISPLAY 0.659574 (-2565 1735);
PAINT MONO (-2565 1735);
DISPLAY INVISIBLE (-2565 1735);
FORCEPROP 1 LAST HDL_POWER P3V3_AUX
J 1
(-2575 1825);
DISPLAY 1.148936 (-2575 1825);
PAINT GREEN (-2575 1825);
FORCEPROP 2 LAST CDS_LIB logical_power
J 0
(-2575 1775);
PAINT MONO (-2575 1775);
DISPLAY INVISIBLE (-2575 1775);
FORCEPROP 1 LAST PATH I13
J 0
(-2525 1800);
DISPLAY 0.872340 (-2525 1800);
PAINT AQUA (-2525 1800);
DISPLAY INVISIBLE (-2525 1800);
FORCEADD TAP..1
(2625 2350);
FORCEPROP 3 LASTPIN (2575 2350) SIG_NAME M_B_CPU0_SB_DQS_DP<4>
J 0
(2585 2360);
DISPLAY 0.659574 (2585 2360);
PAINT MONO (2585 2360);
DISPLAY INVISIBLE (2585 2360);
FORCEPROP 1 LASTPIN (2575 2350) BN 4
J 0
(2563 2358);
DISPLAY 0.680851 (2563 2358);
PAINT GREEN (2563 2358);
FORCEPROP 2 LAST CDS_LIB standard
J 0
(2625 2350);
PAINT MONO (2625 2350);
DISPLAY INVISIBLE (2625 2350);
FORCEPROP 1 LAST BODY_TYPE PLUMBING
J 0
(2625 2400);
DISPLAY 0.872340 (2625 2400);
PAINT GREEN (2625 2400);
DISPLAY INVISIBLE (2625 2400);
FORCEPROP 1 LAST HDL_TAP TRUE
J 0
(2950 2225);
DISPLAY 0.872340 (2950 2225);
DISPLAY INVISIBLE (2950 2225);
FORCEPROP 1 LAST PATH I130
J 0
(2623 2350);
DISPLAY 0.872340 (2623 2350);
PAINT GREEN (2623 2350);
DISPLAY INVISIBLE (2623 2350);
FORCEADD TAP..1
(2625 2450);
FORCEPROP 3 LASTPIN (2575 2450) SIG_NAME M_B_CPU0_SB_DQS_DP<5>
J 0
(2585 2460);
DISPLAY 0.659574 (2585 2460);
PAINT MONO (2585 2460);
DISPLAY INVISIBLE (2585 2460);
FORCEPROP 1 LASTPIN (2575 2450) BN 5
J 0
(2563 2458);
DISPLAY 0.680851 (2563 2458);
PAINT GREEN (2563 2458);
FORCEPROP 2 LAST CDS_LIB standard
J 0
(2625 2450);
DISPLAY INVISIBLE (2625 2450);
FORCEPROP 1 LAST BODY_TYPE PLUMBING
J 0
(2625 2500);
DISPLAY 0.872340 (2625 2500);
PAINT GREEN (2625 2500);
DISPLAY INVISIBLE (2625 2500);
FORCEPROP 1 LAST HDL_TAP TRUE
J 0
(2950 2325);
DISPLAY 0.872340 (2950 2325);
DISPLAY INVISIBLE (2950 2325);
FORCEPROP 1 LAST PATH I131
J 0
(2623 2450);
DISPLAY 0.872340 (2623 2450);
PAINT GREEN (2623 2450);
DISPLAY INVISIBLE (2623 2450);
FORCEADD TAP..1
(2625 2650);
FORCEPROP 3 LASTPIN (2575 2650) SIG_NAME M_B_CPU0_SB_DQS_DP<7>
J 0
(2585 2660);
DISPLAY 0.659574 (2585 2660);
PAINT MONO (2585 2660);
DISPLAY INVISIBLE (2585 2660);
FORCEPROP 1 LASTPIN (2575 2650) BN 7
J 0
(2563 2658);
DISPLAY 0.680851 (2563 2658);
PAINT GREEN (2563 2658);
FORCEPROP 2 LAST CDS_LIB standard
J 0
(2625 2650);
DISPLAY INVISIBLE (2625 2650);
FORCEPROP 1 LAST BODY_TYPE PLUMBING
J 0
(2625 2700);
DISPLAY 0.872340 (2625 2700);
PAINT GREEN (2625 2700);
DISPLAY INVISIBLE (2625 2700);
FORCEPROP 1 LAST HDL_TAP TRUE
J 0
(2950 2525);
DISPLAY 0.872340 (2950 2525);
DISPLAY INVISIBLE (2950 2525);
FORCEPROP 1 LAST PATH I132
J 0
(2623 2650);
DISPLAY 0.872340 (2623 2650);
PAINT GREEN (2623 2650);
DISPLAY INVISIBLE (2623 2650);
FORCEADD TAP..1
(2625 2550);
FORCEPROP 3 LASTPIN (2575 2550) SIG_NAME M_B_CPU0_SB_DQS_DP<6>
J 0
(2585 2560);
DISPLAY 0.659574 (2585 2560);
PAINT MONO (2585 2560);
DISPLAY INVISIBLE (2585 2560);
FORCEPROP 1 LASTPIN (2575 2550) BN 6
J 0
(2563 2558);
DISPLAY 0.680851 (2563 2558);
PAINT GREEN (2563 2558);
FORCEPROP 2 LAST CDS_LIB standard
J 0
(2625 2550);
DISPLAY INVISIBLE (2625 2550);
FORCEPROP 1 LAST BODY_TYPE PLUMBING
J 0
(2625 2600);
DISPLAY 0.872340 (2625 2600);
PAINT GREEN (2625 2600);
DISPLAY INVISIBLE (2625 2600);
FORCEPROP 1 LAST HDL_TAP TRUE
J 0
(2950 2425);
DISPLAY 0.872340 (2950 2425);
DISPLAY INVISIBLE (2950 2425);
FORCEPROP 1 LAST PATH I133
J 0
(2623 2550);
DISPLAY 0.872340 (2623 2550);
PAINT GREEN (2623 2550);
DISPLAY INVISIBLE (2623 2550);
FORCEADD TAP..1
(2625 2750);
FORCEPROP 3 LASTPIN (2575 2750) SIG_NAME M_B_CPU0_SB_DQS_DP<8>
J 0
(2585 2760);
DISPLAY 0.659574 (2585 2760);
PAINT MONO (2585 2760);
DISPLAY INVISIBLE (2585 2760);
FORCEPROP 1 LASTPIN (2575 2750) BN 8
J 0
(2563 2758);
DISPLAY 0.680851 (2563 2758);
PAINT GREEN (2563 2758);
FORCEPROP 2 LAST CDS_LIB standard
J 0
(2625 2750);
DISPLAY INVISIBLE (2625 2750);
FORCEPROP 1 LAST BODY_TYPE PLUMBING
J 0
(2625 2800);
DISPLAY 0.872340 (2625 2800);
PAINT GREEN (2625 2800);
DISPLAY INVISIBLE (2625 2800);
FORCEPROP 1 LAST HDL_TAP TRUE
J 0
(2950 2625);
DISPLAY 0.872340 (2950 2625);
DISPLAY INVISIBLE (2950 2625);
FORCEPROP 1 LAST PATH I134
J 0
(2623 2750);
DISPLAY 0.872340 (2623 2750);
PAINT GREEN (2623 2750);
DISPLAY INVISIBLE (2623 2750);
FORCEADD TAP..1
(2625 2850);
FORCEPROP 3 LASTPIN (2575 2850) SIG_NAME M_B_CPU0_SB_DQS_DP<9>
J 0
(2585 2860);
DISPLAY 0.659574 (2585 2860);
PAINT MONO (2585 2860);
DISPLAY INVISIBLE (2585 2860);
FORCEPROP 1 LASTPIN (2575 2850) BN 9
J 0
(2563 2858);
DISPLAY 0.680851 (2563 2858);
PAINT GREEN (2563 2858);
FORCEPROP 2 LAST CDS_LIB standard
J 0
(2625 2850);
DISPLAY INVISIBLE (2625 2850);
FORCEPROP 1 LAST BODY_TYPE PLUMBING
J 0
(2625 2900);
DISPLAY 0.872340 (2625 2900);
PAINT GREEN (2625 2900);
DISPLAY INVISIBLE (2625 2900);
FORCEPROP 1 LAST HDL_TAP TRUE
J 0
(2950 2725);
DISPLAY 0.872340 (2950 2725);
DISPLAY INVISIBLE (2950 2725);
FORCEPROP 1 LAST PATH I135
J 0
(2623 2850);
DISPLAY 0.872340 (2623 2850);
PAINT GREEN (2623 2850);
DISPLAY INVISIBLE (2623 2850);
FORCEADD TAP..1
(2625 3000);
FORCEPROP 3 LASTPIN (2575 3000) SIG_NAME M_B_CPU0_SA_DQS_DP<0>
J 0
(2585 3010);
DISPLAY 0.659574 (2585 3010);
PAINT MONO (2585 3010);
DISPLAY INVISIBLE (2585 3010);
FORCEPROP 1 LASTPIN (2575 3000) BN 0
J 0
(2563 3008);
DISPLAY 0.680851 (2563 3008);
PAINT GREEN (2563 3008);
FORCEPROP 2 LAST CDS_LIB standard
J 0
(2625 3000);
PAINT MONO (2625 3000);
DISPLAY INVISIBLE (2625 3000);
FORCEPROP 1 LAST BODY_TYPE PLUMBING
J 0
(2625 3050);
DISPLAY 0.872340 (2625 3050);
PAINT GREEN (2625 3050);
DISPLAY INVISIBLE (2625 3050);
FORCEPROP 1 LAST HDL_TAP TRUE
J 0
(2950 2875);
DISPLAY 0.872340 (2950 2875);
DISPLAY INVISIBLE (2950 2875);
FORCEPROP 1 LAST PATH I136
J 0
(2623 3000);
DISPLAY 0.872340 (2623 3000);
PAINT GREEN (2623 3000);
DISPLAY INVISIBLE (2623 3000);
FORCEADD TAP..1
(2625 3100);
FORCEPROP 3 LASTPIN (2575 3100) SIG_NAME M_B_CPU0_SA_DQS_DP<1>
J 0
(2585 3110);
DISPLAY 0.659574 (2585 3110);
PAINT MONO (2585 3110);
DISPLAY INVISIBLE (2585 3110);
FORCEPROP 1 LASTPIN (2575 3100) BN 1
J 0
(2563 3108);
DISPLAY 0.680851 (2563 3108);
PAINT GREEN (2563 3108);
FORCEPROP 2 LAST CDS_LIB standard
J 0
(2625 3100);
DISPLAY INVISIBLE (2625 3100);
FORCEPROP 1 LAST BODY_TYPE PLUMBING
J 0
(2625 3150);
DISPLAY 0.872340 (2625 3150);
PAINT GREEN (2625 3150);
DISPLAY INVISIBLE (2625 3150);
FORCEPROP 1 LAST HDL_TAP TRUE
J 0
(2950 2975);
DISPLAY 0.872340 (2950 2975);
DISPLAY INVISIBLE (2950 2975);
FORCEPROP 1 LAST PATH I137
J 0
(2623 3100);
DISPLAY 0.872340 (2623 3100);
PAINT GREEN (2623 3100);
DISPLAY INVISIBLE (2623 3100);
FORCEADD TAP..1
(2625 3200);
FORCEPROP 3 LASTPIN (2575 3200) SIG_NAME M_B_CPU0_SA_DQS_DP<2>
J 0
(2585 3210);
DISPLAY 0.659574 (2585 3210);
PAINT MONO (2585 3210);
DISPLAY INVISIBLE (2585 3210);
FORCEPROP 1 LASTPIN (2575 3200) BN 2
J 0
(2563 3208);
DISPLAY 0.680851 (2563 3208);
PAINT GREEN (2563 3208);
FORCEPROP 2 LAST CDS_LIB standard
J 0
(2625 3200);
DISPLAY INVISIBLE (2625 3200);
FORCEPROP 1 LAST BODY_TYPE PLUMBING
J 0
(2625 3250);
DISPLAY 0.872340 (2625 3250);
PAINT GREEN (2625 3250);
DISPLAY INVISIBLE (2625 3250);
FORCEPROP 1 LAST HDL_TAP TRUE
J 0
(2950 3075);
DISPLAY 0.872340 (2950 3075);
DISPLAY INVISIBLE (2950 3075);
FORCEPROP 1 LAST PATH I138
J 0
(2623 3200);
DISPLAY 0.872340 (2623 3200);
PAINT GREEN (2623 3200);
DISPLAY INVISIBLE (2623 3200);
FORCEADD TAP..1
(2625 3300);
FORCEPROP 3 LASTPIN (2575 3300) SIG_NAME M_B_CPU0_SA_DQS_DP<3>
J 0
(2585 3310);
DISPLAY 0.659574 (2585 3310);
PAINT MONO (2585 3310);
DISPLAY INVISIBLE (2585 3310);
FORCEPROP 1 LASTPIN (2575 3300) BN 3
J 0
(2563 3308);
DISPLAY 0.680851 (2563 3308);
PAINT GREEN (2563 3308);
FORCEPROP 2 LAST CDS_LIB standard
J 0
(2625 3300);
PAINT MONO (2625 3300);
DISPLAY INVISIBLE (2625 3300);
FORCEPROP 1 LAST BODY_TYPE PLUMBING
J 0
(2625 3350);
DISPLAY 0.872340 (2625 3350);
PAINT GREEN (2625 3350);
DISPLAY INVISIBLE (2625 3350);
FORCEPROP 1 LAST HDL_TAP TRUE
J 0
(2950 3175);
DISPLAY 0.872340 (2950 3175);
DISPLAY INVISIBLE (2950 3175);
FORCEPROP 1 LAST PATH I139
J 0
(2623 3300);
DISPLAY 0.872340 (2623 3300);
PAINT GREEN (2623 3300);
DISPLAY INVISIBLE (2623 3300);
FORCEADD OFFPAGE..3
R 2
(-2675 2525);
FORCEPROP 2 LAST $XR1 85 
J 0
(-3014 2525);
DISPLAY 0.638298 (-3014 2525);
PAINT MONO (-3014 2525);
FORCEPROP 2 LAST $XR0 21 
J 0
(-2924 2525);
DISPLAY 0.638298 (-2924 2525);
PAINT MONO (-2924 2525);
FORCEPROP 2 LAST CDS_LIB standard
J 0
(-2675 2525);
PAINT MONO (-2675 2525);
DISPLAY INVISIBLE (-2675 2525);
FORCEPROP 1 LAST OFFPAGE TRUE
J 2
(-3000 2400);
DISPLAY 0.872340 (-3000 2400);
DISPLAY INVISIBLE (-3000 2400);
FORCEPROP 1 LAST COMMENT_BODY TRUE
J 2
(-2625 2425);
DISPLAY 0.872340 (-2625 2425);
PAINT GREEN (-2625 2425);
DISPLAY INVISIBLE (-2625 2425);
FORCEPROP 2 LAST PATH I14
J 0
(-2625 2600);
DISPLAY 1.021277 (-2625 2600);
DISPLAY INVISIBLE (-2625 2600);
FORCEADD TAP..1
(2625 3400);
FORCEPROP 3 LASTPIN (2575 3400) SIG_NAME M_B_CPU0_SA_DQS_DP<4>
J 0
(2585 3410);
DISPLAY 0.659574 (2585 3410);
PAINT MONO (2585 3410);
DISPLAY INVISIBLE (2585 3410);
FORCEPROP 1 LASTPIN (2575 3400) BN 4
J 0
(2563 3408);
DISPLAY 0.680851 (2563 3408);
PAINT GREEN (2563 3408);
FORCEPROP 2 LAST CDS_LIB standard
J 0
(2625 3400);
PAINT MONO (2625 3400);
DISPLAY INVISIBLE (2625 3400);
FORCEPROP 1 LAST BODY_TYPE PLUMBING
J 0
(2625 3450);
DISPLAY 0.872340 (2625 3450);
PAINT GREEN (2625 3450);
DISPLAY INVISIBLE (2625 3450);
FORCEPROP 1 LAST HDL_TAP TRUE
J 0
(2950 3275);
DISPLAY 0.872340 (2950 3275);
DISPLAY INVISIBLE (2950 3275);
FORCEPROP 1 LAST PATH I140
J 0
(2623 3400);
DISPLAY 0.872340 (2623 3400);
PAINT GREEN (2623 3400);
DISPLAY INVISIBLE (2623 3400);
FORCEADD TAP..1
(2625 3500);
FORCEPROP 3 LASTPIN (2575 3500) SIG_NAME M_B_CPU0_SA_DQS_DP<5>
J 0
(2585 3510);
DISPLAY 0.659574 (2585 3510);
PAINT MONO (2585 3510);
DISPLAY INVISIBLE (2585 3510);
FORCEPROP 1 LASTPIN (2575 3500) BN 5
J 0
(2563 3508);
DISPLAY 0.680851 (2563 3508);
PAINT GREEN (2563 3508);
FORCEPROP 2 LAST CDS_LIB standard
J 0
(2625 3500);
DISPLAY INVISIBLE (2625 3500);
FORCEPROP 1 LAST BODY_TYPE PLUMBING
J 0
(2625 3550);
DISPLAY 0.872340 (2625 3550);
PAINT GREEN (2625 3550);
DISPLAY INVISIBLE (2625 3550);
FORCEPROP 1 LAST HDL_TAP TRUE
J 0
(2950 3375);
DISPLAY 0.872340 (2950 3375);
DISPLAY INVISIBLE (2950 3375);
FORCEPROP 1 LAST PATH I141
J 0
(2623 3500);
DISPLAY 0.872340 (2623 3500);
PAINT GREEN (2623 3500);
DISPLAY INVISIBLE (2623 3500);
FORCEADD TAP..1
(2625 3600);
FORCEPROP 3 LASTPIN (2575 3600) SIG_NAME M_B_CPU0_SA_DQS_DP<6>
J 0
(2585 3610);
DISPLAY 0.659574 (2585 3610);
PAINT MONO (2585 3610);
DISPLAY INVISIBLE (2585 3610);
FORCEPROP 1 LASTPIN (2575 3600) BN 6
J 0
(2563 3608);
DISPLAY 0.680851 (2563 3608);
PAINT GREEN (2563 3608);
FORCEPROP 2 LAST CDS_LIB standard
J 0
(2625 3600);
DISPLAY INVISIBLE (2625 3600);
FORCEPROP 1 LAST BODY_TYPE PLUMBING
J 0
(2625 3650);
DISPLAY 0.872340 (2625 3650);
PAINT GREEN (2625 3650);
DISPLAY INVISIBLE (2625 3650);
FORCEPROP 1 LAST HDL_TAP TRUE
J 0
(2950 3475);
DISPLAY 0.872340 (2950 3475);
DISPLAY INVISIBLE (2950 3475);
FORCEPROP 1 LAST PATH I142
J 0
(2623 3600);
DISPLAY 0.872340 (2623 3600);
PAINT GREEN (2623 3600);
DISPLAY INVISIBLE (2623 3600);
FORCEADD UNIVERSAL_GND..1
(3250 -350);
FORCEPROP 3 LASTPIN (3250 -300) SIG_NAME GND\g
J 0
(3260 -290);
DISPLAY 0.659574 (3260 -290);
PAINT MONO (3260 -290);
DISPLAY INVISIBLE (3260 -290);
FORCEPROP 2 LAST CDS_LIB logical_power
J 0
(3250 -350);
PAINT MONO (3250 -350);
DISPLAY INVISIBLE (3250 -350);
FORCEPROP 1 LAST HDL_POWER GND
J 1
(3275 -425);
DISPLAY 0.872340 (3275 -425);
PAINT GREEN (3275 -425);
DISPLAY INVISIBLE (3275 -425);
FORCEPROP 1 LAST PATH I143
J 0
(3325 -350);
DISPLAY 0.872340 (3325 -350);
PAINT AQUA (3325 -350);
DISPLAY INVISIBLE (3325 -350);
FORCEADD Q_CAP..1
(3250 25);
FORCEPROP 1 LAST PART_NUMBER CH6103KEA00
J 0
(3300 -125);
DISPLAY 0.978723 (3300 -125);
DISPLAY INVISIBLE (3300 -125);
FORCEPROP 1 LAST VALUE 10UF
J 0
(3300 75);
DISPLAY 0.978723 (3300 75);
FORCEPROP 1 LAST VOLTAGE 16V
J 0
(3300 25);
DISPLAY 0.978723 (3300 25);
FORCEPROP 1 LAST TOLERANCE 10%
J 0
(3300 -25);
DISPLAY 0.978723 (3300 -25);
FORCEPROP 1 LAST PACK_TYPE C0805
J 0
(3300 -175);
DISPLAY 0.978723 (3300 -175);
FORCEPROP 1 LAST MATERIAL X6S
J 0
(3300 -75);
DISPLAY 0.978723 (3300 -75);
FORCEPROP 1 LAST $LOCATION C10
J 0
(3300 125);
DISPLAY 0.978723 (3300 125);
FORCEPROP 1 LASTPIN (3250 125) $PN 1
J 0
(3260 105);
DISPLAY 0.787234 (3260 105);
FORCEPROP 1 LASTPIN (3250 -75) $PN 2
J 0
(3260 -95);
DISPLAY 0.787234 (3260 -95);
FORCEPROP 2 LAST CDS_LIB pure_quanta
J 0
(3250 25);
PAINT MONO (3250 25);
DISPLAY INVISIBLE (3250 25);
FORCEPROP 2 LAST CDS_LOCATION C10
J 0
(3300 225);
DISPLAY 1.021277 (3300 225);
DISPLAY INVISIBLE (3300 225);
FORCEPROP 2 LAST $SEC 1
J 0
(3300 225);
DISPLAY 0.680851 (3300 225);
PAINT MONO (3300 225);
DISPLAY INVISIBLE (3300 225);
FORCEPROP 2 LAST CDS_SEC 1
J 0
(3300 225);
DISPLAY 1.021277 (3300 225);
DISPLAY INVISIBLE (3300 225);
FORCEPROP 1 LAST PATH I144
J 0
(3300 175);
DISPLAY 0.978723 (3300 175);
PAINT WHITE (3300 175);
DISPLAY INVISIBLE (3300 175);
FORCEADD UNIVERSAL_GND..1
(4325 200);
FORCEPROP 3 LASTPIN (4325 250) SIG_NAME GND\g
J 0
(4335 260);
DISPLAY 0.659574 (4335 260);
PAINT MONO (4335 260);
DISPLAY INVISIBLE (4335 260);
FORCEPROP 2 LAST CDS_LIB logical_power
J 0
(4325 200);
PAINT MONO (4325 200);
DISPLAY INVISIBLE (4325 200);
FORCEPROP 1 LAST HDL_POWER GND
J 1
(4350 125);
DISPLAY 0.872340 (4350 125);
PAINT GREEN (4350 125);
DISPLAY INVISIBLE (4350 125);
FORCEPROP 1 LAST PATH I145
J 0
(4400 200);
DISPLAY 0.872340 (4400 200);
PAINT AQUA (4400 200);
DISPLAY INVISIBLE (4400 200);
FORCEADD TAP..1
(2800 1900);
FORCEPROP 3 LASTPIN (2750 1900) SIG_NAME M_B_CPU0_SB_DQS_DN<0>
J 0
(2760 1910);
DISPLAY 0.659574 (2760 1910);
PAINT MONO (2760 1910);
DISPLAY INVISIBLE (2760 1910);
FORCEPROP 1 LASTPIN (2750 1900) BN 0
J 0
(2738 1908);
DISPLAY 0.680851 (2738 1908);
PAINT GREEN (2738 1908);
FORCEPROP 2 LAST CDS_LIB standard
J 0
(2800 1900);
PAINT MONO (2800 1900);
DISPLAY INVISIBLE (2800 1900);
FORCEPROP 1 LAST BODY_TYPE PLUMBING
J 0
(2800 1950);
DISPLAY 0.872340 (2800 1950);
PAINT GREEN (2800 1950);
DISPLAY INVISIBLE (2800 1950);
FORCEPROP 1 LAST HDL_TAP TRUE
J 0
(3125 1775);
DISPLAY 0.872340 (3125 1775);
DISPLAY INVISIBLE (3125 1775);
FORCEPROP 1 LAST PATH I147
J 0
(2798 1900);
DISPLAY 0.872340 (2798 1900);
PAINT GREEN (2798 1900);
DISPLAY INVISIBLE (2798 1900);
FORCEADD TAP..1
(2800 2000);
FORCEPROP 3 LASTPIN (2750 2000) SIG_NAME M_B_CPU0_SB_DQS_DN<1>
J 0
(2760 2010);
DISPLAY 0.659574 (2760 2010);
PAINT MONO (2760 2010);
DISPLAY INVISIBLE (2760 2010);
FORCEPROP 1 LASTPIN (2750 2000) BN 1
J 0
(2738 2008);
DISPLAY 0.680851 (2738 2008);
PAINT GREEN (2738 2008);
FORCEPROP 2 LAST CDS_LIB standard
J 0
(2800 2000);
DISPLAY INVISIBLE (2800 2000);
FORCEPROP 1 LAST BODY_TYPE PLUMBING
J 0
(2800 2050);
DISPLAY 0.872340 (2800 2050);
PAINT GREEN (2800 2050);
DISPLAY INVISIBLE (2800 2050);
FORCEPROP 1 LAST HDL_TAP TRUE
J 0
(3125 1875);
DISPLAY 0.872340 (3125 1875);
DISPLAY INVISIBLE (3125 1875);
FORCEPROP 1 LAST PATH I148
J 0
(2798 2000);
DISPLAY 0.872340 (2798 2000);
PAINT GREEN (2798 2000);
DISPLAY INVISIBLE (2798 2000);
FORCEADD TAP..1
(2800 2100);
FORCEPROP 3 LASTPIN (2750 2100) SIG_NAME M_B_CPU0_SB_DQS_DN<2>
J 0
(2760 2110);
DISPLAY 0.659574 (2760 2110);
PAINT MONO (2760 2110);
DISPLAY INVISIBLE (2760 2110);
FORCEPROP 1 LASTPIN (2750 2100) BN 2
J 0
(2738 2108);
DISPLAY 0.680851 (2738 2108);
PAINT GREEN (2738 2108);
FORCEPROP 2 LAST CDS_LIB standard
J 0
(2800 2100);
DISPLAY INVISIBLE (2800 2100);
FORCEPROP 1 LAST BODY_TYPE PLUMBING
J 0
(2800 2150);
DISPLAY 0.872340 (2800 2150);
PAINT GREEN (2800 2150);
DISPLAY INVISIBLE (2800 2150);
FORCEPROP 1 LAST HDL_TAP TRUE
J 0
(3125 1975);
DISPLAY 0.872340 (3125 1975);
DISPLAY INVISIBLE (3125 1975);
FORCEPROP 1 LAST PATH I149
J 0
(2798 2100);
DISPLAY 0.872340 (2798 2100);
PAINT GREEN (2798 2100);
DISPLAY INVISIBLE (2798 2100);
FORCEADD OFFPAGE..1
(-2675 2600);
FORCEPROP 2 LAST $XR0 21 
J 0
(-2896 2600);
DISPLAY 0.638298 (-2896 2600);
PAINT MONO (-2896 2600);
FORCEPROP 2 LAST CDS_LIB standard
J 0
(-2675 2600);
PAINT MONO (-2675 2600);
DISPLAY INVISIBLE (-2675 2600);
FORCEPROP 1 LAST OFFPAGE TRUE
J 0
(-2350 2475);
DISPLAY 0.872340 (-2350 2475);
DISPLAY INVISIBLE (-2350 2475);
FORCEPROP 1 LAST COMMENT_BODY TRUE
J 0
(-2550 2500);
DISPLAY 0.872340 (-2550 2500);
PAINT GREEN (-2550 2500);
DISPLAY INVISIBLE (-2550 2500);
FORCEPROP 2 LAST PATH I15
J 0
(-2625 2675);
DISPLAY 1.021277 (-2625 2675);
DISPLAY INVISIBLE (-2625 2675);
FORCEADD TAP..1
(2800 2200);
FORCEPROP 3 LASTPIN (2750 2200) SIG_NAME M_B_CPU0_SB_DQS_DN<3>
J 0
(2760 2210);
DISPLAY 0.659574 (2760 2210);
PAINT MONO (2760 2210);
DISPLAY INVISIBLE (2760 2210);
FORCEPROP 1 LASTPIN (2750 2200) BN 3
J 0
(2738 2208);
DISPLAY 0.680851 (2738 2208);
PAINT GREEN (2738 2208);
FORCEPROP 2 LAST CDS_LIB standard
J 0
(2800 2200);
PAINT MONO (2800 2200);
DISPLAY INVISIBLE (2800 2200);
FORCEPROP 1 LAST BODY_TYPE PLUMBING
J 0
(2800 2250);
DISPLAY 0.872340 (2800 2250);
PAINT GREEN (2800 2250);
DISPLAY INVISIBLE (2800 2250);
FORCEPROP 1 LAST HDL_TAP TRUE
J 0
(3125 2075);
DISPLAY 0.872340 (3125 2075);
DISPLAY INVISIBLE (3125 2075);
FORCEPROP 1 LAST PATH I150
J 0
(2798 2200);
DISPLAY 0.872340 (2798 2200);
PAINT GREEN (2798 2200);
DISPLAY INVISIBLE (2798 2200);
FORCEADD TAP..1
(2800 2400);
FORCEPROP 3 LASTPIN (2750 2400) SIG_NAME M_B_CPU0_SB_DQS_DN<5>
J 0
(2760 2410);
DISPLAY 0.659574 (2760 2410);
PAINT MONO (2760 2410);
DISPLAY INVISIBLE (2760 2410);
FORCEPROP 1 LASTPIN (2750 2400) BN 5
J 0
(2738 2408);
DISPLAY 0.680851 (2738 2408);
PAINT GREEN (2738 2408);
FORCEPROP 2 LAST CDS_LIB standard
J 0
(2800 2400);
DISPLAY INVISIBLE (2800 2400);
FORCEPROP 1 LAST BODY_TYPE PLUMBING
J 0
(2800 2450);
DISPLAY 0.872340 (2800 2450);
PAINT GREEN (2800 2450);
DISPLAY INVISIBLE (2800 2450);
FORCEPROP 1 LAST HDL_TAP TRUE
J 0
(3125 2275);
DISPLAY 0.872340 (3125 2275);
DISPLAY INVISIBLE (3125 2275);
FORCEPROP 1 LAST PATH I151
J 0
(2798 2400);
DISPLAY 0.872340 (2798 2400);
PAINT GREEN (2798 2400);
DISPLAY INVISIBLE (2798 2400);
FORCEADD TAP..1
(2800 2300);
FORCEPROP 3 LASTPIN (2750 2300) SIG_NAME M_B_CPU0_SB_DQS_DN<4>
J 0
(2760 2310);
DISPLAY 0.659574 (2760 2310);
PAINT MONO (2760 2310);
DISPLAY INVISIBLE (2760 2310);
FORCEPROP 1 LASTPIN (2750 2300) BN 4
J 0
(2738 2308);
DISPLAY 0.680851 (2738 2308);
PAINT GREEN (2738 2308);
FORCEPROP 2 LAST CDS_LIB standard
J 0
(2800 2300);
PAINT MONO (2800 2300);
DISPLAY INVISIBLE (2800 2300);
FORCEPROP 1 LAST BODY_TYPE PLUMBING
J 0
(2800 2350);
DISPLAY 0.872340 (2800 2350);
PAINT GREEN (2800 2350);
DISPLAY INVISIBLE (2800 2350);
FORCEPROP 1 LAST HDL_TAP TRUE
J 0
(3125 2175);
DISPLAY 0.872340 (3125 2175);
DISPLAY INVISIBLE (3125 2175);
FORCEPROP 1 LAST PATH I152
J 0
(2798 2300);
DISPLAY 0.872340 (2798 2300);
PAINT GREEN (2798 2300);
DISPLAY INVISIBLE (2798 2300);
FORCEADD TAP..1
(2800 2500);
FORCEPROP 3 LASTPIN (2750 2500) SIG_NAME M_B_CPU0_SB_DQS_DN<6>
J 0
(2760 2510);
DISPLAY 0.659574 (2760 2510);
PAINT MONO (2760 2510);
DISPLAY INVISIBLE (2760 2510);
FORCEPROP 1 LASTPIN (2750 2500) BN 6
J 0
(2738 2508);
DISPLAY 0.680851 (2738 2508);
PAINT GREEN (2738 2508);
FORCEPROP 2 LAST CDS_LIB standard
J 0
(2800 2500);
DISPLAY INVISIBLE (2800 2500);
FORCEPROP 1 LAST BODY_TYPE PLUMBING
J 0
(2800 2550);
DISPLAY 0.872340 (2800 2550);
PAINT GREEN (2800 2550);
DISPLAY INVISIBLE (2800 2550);
FORCEPROP 1 LAST HDL_TAP TRUE
J 0
(3125 2375);
DISPLAY 0.872340 (3125 2375);
DISPLAY INVISIBLE (3125 2375);
FORCEPROP 1 LAST PATH I153
J 0
(2798 2500);
DISPLAY 0.872340 (2798 2500);
PAINT GREEN (2798 2500);
DISPLAY INVISIBLE (2798 2500);
FORCEADD TAP..1
(2800 2600);
FORCEPROP 3 LASTPIN (2750 2600) SIG_NAME M_B_CPU0_SB_DQS_DN<7>
J 0
(2760 2610);
DISPLAY 0.659574 (2760 2610);
PAINT MONO (2760 2610);
DISPLAY INVISIBLE (2760 2610);
FORCEPROP 1 LASTPIN (2750 2600) BN 7
J 0
(2738 2608);
DISPLAY 0.680851 (2738 2608);
PAINT GREEN (2738 2608);
FORCEPROP 2 LAST CDS_LIB standard
J 0
(2800 2600);
DISPLAY INVISIBLE (2800 2600);
FORCEPROP 1 LAST BODY_TYPE PLUMBING
J 0
(2800 2650);
DISPLAY 0.872340 (2800 2650);
PAINT GREEN (2800 2650);
DISPLAY INVISIBLE (2800 2650);
FORCEPROP 1 LAST HDL_TAP TRUE
J 0
(3125 2475);
DISPLAY 0.872340 (3125 2475);
DISPLAY INVISIBLE (3125 2475);
FORCEPROP 1 LAST PATH I154
J 0
(2798 2600);
DISPLAY 0.872340 (2798 2600);
PAINT GREEN (2798 2600);
DISPLAY INVISIBLE (2798 2600);
FORCEADD TAP..1
(2800 2700);
FORCEPROP 3 LASTPIN (2750 2700) SIG_NAME M_B_CPU0_SB_DQS_DN<8>
J 0
(2760 2710);
DISPLAY 0.659574 (2760 2710);
PAINT MONO (2760 2710);
DISPLAY INVISIBLE (2760 2710);
FORCEPROP 1 LASTPIN (2750 2700) BN 8
J 0
(2738 2708);
DISPLAY 0.680851 (2738 2708);
PAINT GREEN (2738 2708);
FORCEPROP 2 LAST CDS_LIB standard
J 0
(2800 2700);
DISPLAY INVISIBLE (2800 2700);
FORCEPROP 1 LAST BODY_TYPE PLUMBING
J 0
(2800 2750);
DISPLAY 0.872340 (2800 2750);
PAINT GREEN (2800 2750);
DISPLAY INVISIBLE (2800 2750);
FORCEPROP 1 LAST HDL_TAP TRUE
J 0
(3125 2575);
DISPLAY 0.872340 (3125 2575);
DISPLAY INVISIBLE (3125 2575);
FORCEPROP 1 LAST PATH I155
J 0
(2798 2700);
DISPLAY 0.872340 (2798 2700);
PAINT GREEN (2798 2700);
DISPLAY INVISIBLE (2798 2700);
FORCEADD TAP..1
(2800 2800);
FORCEPROP 3 LASTPIN (2750 2800) SIG_NAME M_B_CPU0_SB_DQS_DN<9>
J 0
(2760 2810);
DISPLAY 0.659574 (2760 2810);
PAINT MONO (2760 2810);
DISPLAY INVISIBLE (2760 2810);
FORCEPROP 1 LASTPIN (2750 2800) BN 9
J 0
(2738 2808);
DISPLAY 0.680851 (2738 2808);
PAINT GREEN (2738 2808);
FORCEPROP 2 LAST CDS_LIB standard
J 0
(2800 2800);
DISPLAY INVISIBLE (2800 2800);
FORCEPROP 1 LAST BODY_TYPE PLUMBING
J 0
(2800 2850);
DISPLAY 0.872340 (2800 2850);
PAINT GREEN (2800 2850);
DISPLAY INVISIBLE (2800 2850);
FORCEPROP 1 LAST HDL_TAP TRUE
J 0
(3125 2675);
DISPLAY 0.872340 (3125 2675);
DISPLAY INVISIBLE (3125 2675);
FORCEPROP 1 LAST PATH I156
J 0
(2798 2800);
DISPLAY 0.872340 (2798 2800);
PAINT GREEN (2798 2800);
DISPLAY INVISIBLE (2798 2800);
FORCEADD TAP..1
(2800 3050);
FORCEPROP 3 LASTPIN (2750 3050) SIG_NAME M_B_CPU0_SA_DQS_DN<1>
J 0
(2760 3060);
DISPLAY 0.659574 (2760 3060);
PAINT MONO (2760 3060);
DISPLAY INVISIBLE (2760 3060);
FORCEPROP 1 LASTPIN (2750 3050) BN 1
J 0
(2738 3058);
DISPLAY 0.680851 (2738 3058);
PAINT GREEN (2738 3058);
FORCEPROP 2 LAST CDS_LIB standard
J 0
(2800 3050);
DISPLAY INVISIBLE (2800 3050);
FORCEPROP 1 LAST BODY_TYPE PLUMBING
J 0
(2800 3100);
DISPLAY 0.872340 (2800 3100);
PAINT GREEN (2800 3100);
DISPLAY INVISIBLE (2800 3100);
FORCEPROP 1 LAST HDL_TAP TRUE
J 0
(3125 2925);
DISPLAY 0.872340 (3125 2925);
DISPLAY INVISIBLE (3125 2925);
FORCEPROP 1 LAST PATH I157
J 0
(2798 3050);
DISPLAY 0.872340 (2798 3050);
PAINT GREEN (2798 3050);
DISPLAY INVISIBLE (2798 3050);
FORCEADD TAP..1
(2800 2950);
FORCEPROP 3 LASTPIN (2750 2950) SIG_NAME M_B_CPU0_SA_DQS_DN<0>
J 0
(2760 2960);
DISPLAY 0.659574 (2760 2960);
PAINT MONO (2760 2960);
DISPLAY INVISIBLE (2760 2960);
FORCEPROP 1 LASTPIN (2750 2950) BN 0
J 0
(2738 2958);
DISPLAY 0.680851 (2738 2958);
PAINT GREEN (2738 2958);
FORCEPROP 2 LAST CDS_LIB standard
J 0
(2800 2950);
PAINT MONO (2800 2950);
DISPLAY INVISIBLE (2800 2950);
FORCEPROP 1 LAST BODY_TYPE PLUMBING
J 0
(2800 3000);
DISPLAY 0.872340 (2800 3000);
PAINT GREEN (2800 3000);
DISPLAY INVISIBLE (2800 3000);
FORCEPROP 1 LAST HDL_TAP TRUE
J 0
(3125 2825);
DISPLAY 0.872340 (3125 2825);
DISPLAY INVISIBLE (3125 2825);
FORCEPROP 1 LAST PATH I158
J 0
(2798 2950);
DISPLAY 0.872340 (2798 2950);
PAINT GREEN (2798 2950);
DISPLAY INVISIBLE (2798 2950);
FORCEADD TAP..1
(2800 3150);
FORCEPROP 3 LASTPIN (2750 3150) SIG_NAME M_B_CPU0_SA_DQS_DN<2>
J 0
(2760 3160);
DISPLAY 0.659574 (2760 3160);
PAINT MONO (2760 3160);
DISPLAY INVISIBLE (2760 3160);
FORCEPROP 1 LASTPIN (2750 3150) BN 2
J 0
(2738 3158);
DISPLAY 0.680851 (2738 3158);
PAINT GREEN (2738 3158);
FORCEPROP 2 LAST CDS_LIB standard
J 0
(2800 3150);
DISPLAY INVISIBLE (2800 3150);
FORCEPROP 1 LAST BODY_TYPE PLUMBING
J 0
(2800 3200);
DISPLAY 0.872340 (2800 3200);
PAINT GREEN (2800 3200);
DISPLAY INVISIBLE (2800 3200);
FORCEPROP 1 LAST HDL_TAP TRUE
J 0
(3125 3025);
DISPLAY 0.872340 (3125 3025);
DISPLAY INVISIBLE (3125 3025);
FORCEPROP 1 LAST PATH I159
J 0
(2798 3150);
DISPLAY 0.872340 (2798 3150);
PAINT GREEN (2798 3150);
DISPLAY INVISIBLE (2798 3150);
FORCEADD OFFPAGE..1
(-2675 2650);
FORCEPROP 2 LAST $XR0 21 
J 0
(-2896 2650);
DISPLAY 0.638298 (-2896 2650);
PAINT MONO (-2896 2650);
FORCEPROP 2 LAST CDS_LIB standard
J 0
(-2675 2650);
PAINT MONO (-2675 2650);
DISPLAY INVISIBLE (-2675 2650);
FORCEPROP 1 LAST OFFPAGE TRUE
J 0
(-2350 2525);
DISPLAY 0.872340 (-2350 2525);
DISPLAY INVISIBLE (-2350 2525);
FORCEPROP 1 LAST COMMENT_BODY TRUE
J 0
(-2550 2550);
DISPLAY 0.872340 (-2550 2550);
PAINT GREEN (-2550 2550);
DISPLAY INVISIBLE (-2550 2550);
FORCEPROP 2 LAST PATH I16
J 0
(-2625 2725);
DISPLAY 1.021277 (-2625 2725);
DISPLAY INVISIBLE (-2625 2725);
FORCEADD TAP..1
(2800 3250);
FORCEPROP 3 LASTPIN (2750 3250) SIG_NAME M_B_CPU0_SA_DQS_DN<3>
J 0
(2760 3260);
DISPLAY 0.659574 (2760 3260);
PAINT MONO (2760 3260);
DISPLAY INVISIBLE (2760 3260);
FORCEPROP 1 LASTPIN (2750 3250) BN 3
J 0
(2738 3258);
DISPLAY 0.680851 (2738 3258);
PAINT GREEN (2738 3258);
FORCEPROP 2 LAST CDS_LIB standard
J 0
(2800 3250);
PAINT MONO (2800 3250);
DISPLAY INVISIBLE (2800 3250);
FORCEPROP 1 LAST BODY_TYPE PLUMBING
J 0
(2800 3300);
DISPLAY 0.872340 (2800 3300);
PAINT GREEN (2800 3300);
DISPLAY INVISIBLE (2800 3300);
FORCEPROP 1 LAST HDL_TAP TRUE
J 0
(3125 3125);
DISPLAY 0.872340 (3125 3125);
DISPLAY INVISIBLE (3125 3125);
FORCEPROP 1 LAST PATH I160
J 0
(2798 3250);
DISPLAY 0.872340 (2798 3250);
PAINT GREEN (2798 3250);
DISPLAY INVISIBLE (2798 3250);
FORCEADD TAP..1
(2800 3350);
FORCEPROP 3 LASTPIN (2750 3350) SIG_NAME M_B_CPU0_SA_DQS_DN<4>
J 0
(2760 3360);
DISPLAY 0.659574 (2760 3360);
PAINT MONO (2760 3360);
DISPLAY INVISIBLE (2760 3360);
FORCEPROP 1 LASTPIN (2750 3350) BN 4
J 0
(2738 3358);
DISPLAY 0.680851 (2738 3358);
PAINT GREEN (2738 3358);
FORCEPROP 2 LAST CDS_LIB standard
J 0
(2800 3350);
PAINT MONO (2800 3350);
DISPLAY INVISIBLE (2800 3350);
FORCEPROP 1 LAST BODY_TYPE PLUMBING
J 0
(2800 3400);
DISPLAY 0.872340 (2800 3400);
PAINT GREEN (2800 3400);
DISPLAY INVISIBLE (2800 3400);
FORCEPROP 1 LAST HDL_TAP TRUE
J 0
(3125 3225);
DISPLAY 0.872340 (3125 3225);
DISPLAY INVISIBLE (3125 3225);
FORCEPROP 1 LAST PATH I161
J 0
(2798 3350);
DISPLAY 0.872340 (2798 3350);
PAINT GREEN (2798 3350);
DISPLAY INVISIBLE (2798 3350);
FORCEADD TAP..1
(2800 3550);
FORCEPROP 3 LASTPIN (2750 3550) SIG_NAME M_B_CPU0_SA_DQS_DN<6>
J 0
(2760 3560);
DISPLAY 0.659574 (2760 3560);
PAINT MONO (2760 3560);
DISPLAY INVISIBLE (2760 3560);
FORCEPROP 1 LASTPIN (2750 3550) BN 6
J 0
(2738 3558);
DISPLAY 0.680851 (2738 3558);
PAINT GREEN (2738 3558);
FORCEPROP 2 LAST CDS_LIB standard
J 0
(2800 3550);
DISPLAY INVISIBLE (2800 3550);
FORCEPROP 1 LAST BODY_TYPE PLUMBING
J 0
(2800 3600);
DISPLAY 0.872340 (2800 3600);
PAINT GREEN (2800 3600);
DISPLAY INVISIBLE (2800 3600);
FORCEPROP 1 LAST HDL_TAP TRUE
J 0
(3125 3425);
DISPLAY 0.872340 (3125 3425);
DISPLAY INVISIBLE (3125 3425);
FORCEPROP 1 LAST PATH I162
J 0
(2798 3550);
DISPLAY 0.872340 (2798 3550);
PAINT GREEN (2798 3550);
DISPLAY INVISIBLE (2798 3550);
FORCEADD TAP..1
(2800 3450);
FORCEPROP 3 LASTPIN (2750 3450) SIG_NAME M_B_CPU0_SA_DQS_DN<5>
J 0
(2760 3460);
DISPLAY 0.659574 (2760 3460);
PAINT MONO (2760 3460);
DISPLAY INVISIBLE (2760 3460);
FORCEPROP 1 LASTPIN (2750 3450) BN 5
J 0
(2738 3458);
DISPLAY 0.680851 (2738 3458);
PAINT GREEN (2738 3458);
FORCEPROP 2 LAST CDS_LIB standard
J 0
(2800 3450);
DISPLAY INVISIBLE (2800 3450);
FORCEPROP 1 LAST BODY_TYPE PLUMBING
J 0
(2800 3500);
DISPLAY 0.872340 (2800 3500);
PAINT GREEN (2800 3500);
DISPLAY INVISIBLE (2800 3500);
FORCEPROP 1 LAST HDL_TAP TRUE
J 0
(3125 3325);
DISPLAY 0.872340 (3125 3325);
DISPLAY INVISIBLE (3125 3325);
FORCEPROP 1 LAST PATH I163
J 0
(2798 3450);
DISPLAY 0.872340 (2798 3450);
PAINT GREEN (2798 3450);
DISPLAY INVISIBLE (2798 3450);
FORCEADD TAP..1
(2800 3650);
FORCEPROP 3 LASTPIN (2750 3650) SIG_NAME M_B_CPU0_SA_DQS_DN<7>
J 0
(2760 3660);
DISPLAY 0.659574 (2760 3660);
PAINT MONO (2760 3660);
DISPLAY INVISIBLE (2760 3660);
FORCEPROP 1 LASTPIN (2750 3650) BN 7
J 0
(2738 3658);
DISPLAY 0.680851 (2738 3658);
PAINT GREEN (2738 3658);
FORCEPROP 2 LAST CDS_LIB standard
J 0
(2800 3650);
DISPLAY INVISIBLE (2800 3650);
FORCEPROP 1 LAST BODY_TYPE PLUMBING
J 0
(2800 3700);
DISPLAY 0.872340 (2800 3700);
PAINT GREEN (2800 3700);
DISPLAY INVISIBLE (2800 3700);
FORCEPROP 1 LAST HDL_TAP TRUE
J 0
(3125 3525);
DISPLAY 0.872340 (3125 3525);
DISPLAY INVISIBLE (3125 3525);
FORCEPROP 1 LAST PATH I164
J 0
(2798 3650);
DISPLAY 0.872340 (2798 3650);
PAINT GREEN (2798 3650);
DISPLAY INVISIBLE (2798 3650);
FORCEADD OFFPAGE..2
(3750 2825);
FORCEPROP 2 LAST $XR1 85 
J 0
(4029 2825);
DISPLAY 0.638298 (4029 2825);
PAINT MONO (4029 2825);
FORCEPROP 2 LAST $XR0 21 
J 0
(3939 2825);
DISPLAY 0.638298 (3939 2825);
PAINT MONO (3939 2825);
FORCEPROP 2 LAST CDS_LIB standard
J 0
(3750 2825);
PAINT MONO (3750 2825);
DISPLAY INVISIBLE (3750 2825);
FORCEPROP 1 LAST OFFPAGE TRUE
J 0
(4075 2700);
DISPLAY 1.170213 (4075 2700);
PAINT GREEN (4075 2700);
DISPLAY INVISIBLE (4075 2700);
FORCEPROP 1 LAST COMMENT_BODY TRUE
J 0
(3705 2730);
DISPLAY 1.170213 (3705 2730);
PAINT GREEN (3705 2730);
DISPLAY INVISIBLE (3705 2730);
FORCEPROP 2 LAST PATH I165
J 0
(3925 2900);
DISPLAY 1.021277 (3925 2900);
DISPLAY INVISIBLE (3925 2900);
FORCEADD OFFPAGE..2
(3750 2875);
FORCEPROP 2 LAST $XR1 85 
J 0
(4029 2875);
DISPLAY 0.638298 (4029 2875);
PAINT MONO (4029 2875);
FORCEPROP 2 LAST $XR0 21 
J 0
(3939 2875);
DISPLAY 0.638298 (3939 2875);
PAINT MONO (3939 2875);
FORCEPROP 2 LAST CDS_LIB standard
J 0
(3750 2875);
PAINT MONO (3750 2875);
DISPLAY INVISIBLE (3750 2875);
FORCEPROP 1 LAST OFFPAGE TRUE
J 0
(4075 2750);
DISPLAY 1.170213 (4075 2750);
PAINT GREEN (4075 2750);
DISPLAY INVISIBLE (4075 2750);
FORCEPROP 1 LAST COMMENT_BODY TRUE
J 0
(3705 2780);
DISPLAY 1.170213 (3705 2780);
PAINT GREEN (3705 2780);
DISPLAY INVISIBLE (3705 2780);
FORCEPROP 2 LAST PATH I166
J 0
(3925 2950);
DISPLAY 1.021277 (3925 2950);
DISPLAY INVISIBLE (3925 2950);
FORCEADD OFFPAGE..3
(725 3925);
FORCEPROP 2 LAST $XR1 85 
J 0
(1029 3925);
DISPLAY 0.638298 (1029 3925);
PAINT MONO (1029 3925);
FORCEPROP 2 LAST $XR0 21 
J 0
(939 3925);
DISPLAY 0.638298 (939 3925);
PAINT MONO (939 3925);
FORCEPROP 2 LAST CDS_LIB standard
J 2
(725 3925);
DISPLAY INVISIBLE (725 3925);
FORCEPROP 1 LAST OFFPAGE TRUE
J 0
(1050 3800);
DISPLAY 0.872340 (1050 3800);
DISPLAY INVISIBLE (1050 3800);
FORCEPROP 1 LAST COMMENT_BODY TRUE
J 0
(675 3825);
DISPLAY 0.872340 (675 3825);
PAINT GREEN (675 3825);
DISPLAY INVISIBLE (675 3825);
FORCEPROP 2 LAST PATH I167
J 0
(925 4000);
DISPLAY 1.021277 (925 4000);
DISPLAY INVISIBLE (925 4000);
FORCEADD TAP..1
(2625 3700);
FORCEPROP 3 LASTPIN (2575 3700) SIG_NAME M_B_CPU0_SA_DQS_DP<7>
J 0
(2585 3710);
DISPLAY 0.659574 (2585 3710);
PAINT MONO (2585 3710);
DISPLAY INVISIBLE (2585 3710);
FORCEPROP 1 LASTPIN (2575 3700) BN 7
J 0
(2563 3708);
DISPLAY 0.680851 (2563 3708);
PAINT GREEN (2563 3708);
FORCEPROP 2 LAST CDS_LIB standard
J 0
(2625 3700);
DISPLAY INVISIBLE (2625 3700);
FORCEPROP 1 LAST BODY_TYPE PLUMBING
J 0
(2625 3750);
DISPLAY 0.872340 (2625 3750);
PAINT GREEN (2625 3750);
DISPLAY INVISIBLE (2625 3750);
FORCEPROP 1 LAST HDL_TAP TRUE
J 0
(2950 3575);
DISPLAY 0.872340 (2950 3575);
DISPLAY INVISIBLE (2950 3575);
FORCEPROP 1 LAST PATH I168
J 0
(2623 3700);
DISPLAY 0.872340 (2623 3700);
PAINT GREEN (2623 3700);
DISPLAY INVISIBLE (2623 3700);
FORCEADD TAP..1
(2625 3800);
FORCEPROP 3 LASTPIN (2575 3800) SIG_NAME M_B_CPU0_SA_DQS_DP<8>
J 0
(2585 3810);
DISPLAY 0.659574 (2585 3810);
PAINT MONO (2585 3810);
DISPLAY INVISIBLE (2585 3810);
FORCEPROP 1 LASTPIN (2575 3800) BN 8
J 0
(2563 3808);
DISPLAY 0.680851 (2563 3808);
PAINT GREEN (2563 3808);
FORCEPROP 2 LAST CDS_LIB standard
J 0
(2625 3800);
DISPLAY INVISIBLE (2625 3800);
FORCEPROP 1 LAST BODY_TYPE PLUMBING
J 0
(2625 3850);
DISPLAY 0.872340 (2625 3850);
PAINT GREEN (2625 3850);
DISPLAY INVISIBLE (2625 3850);
FORCEPROP 1 LAST HDL_TAP TRUE
J 0
(2950 3675);
DISPLAY 0.872340 (2950 3675);
DISPLAY INVISIBLE (2950 3675);
FORCEPROP 1 LAST PATH I169
J 0
(2623 3800);
DISPLAY 0.872340 (2623 3800);
PAINT GREEN (2623 3800);
DISPLAY INVISIBLE (2623 3800);
FORCEADD OFFPAGE..1
(-2675 2900);
FORCEPROP 2 LAST $XR0 21 
J 0
(-2896 2900);
DISPLAY 0.638298 (-2896 2900);
PAINT MONO (-2896 2900);
FORCEPROP 2 LAST CDS_LIB standard
J 0
(-2675 2900);
PAINT MONO (-2675 2900);
DISPLAY INVISIBLE (-2675 2900);
FORCEPROP 1 LAST OFFPAGE TRUE
J 0
(-2350 2775);
DISPLAY 0.872340 (-2350 2775);
DISPLAY INVISIBLE (-2350 2775);
FORCEPROP 1 LAST COMMENT_BODY TRUE
J 0
(-2550 2800);
DISPLAY 0.872340 (-2550 2800);
PAINT GREEN (-2550 2800);
DISPLAY INVISIBLE (-2550 2800);
FORCEPROP 2 LAST PATH I17
J 0
(-2625 2975);
DISPLAY 1.021277 (-2625 2975);
DISPLAY INVISIBLE (-2625 2975);
FORCEADD TAP..1
(2625 3900);
FORCEPROP 3 LASTPIN (2575 3900) SIG_NAME M_B_CPU0_SA_DQS_DP<9>
J 0
(2585 3910);
DISPLAY 0.659574 (2585 3910);
PAINT MONO (2585 3910);
DISPLAY INVISIBLE (2585 3910);
FORCEPROP 1 LASTPIN (2575 3900) BN 9
J 0
(2563 3908);
DISPLAY 0.680851 (2563 3908);
PAINT GREEN (2563 3908);
FORCEPROP 2 LAST CDS_LIB standard
J 0
(2625 3900);
DISPLAY INVISIBLE (2625 3900);
FORCEPROP 1 LAST BODY_TYPE PLUMBING
J 0
(2625 3950);
DISPLAY 0.872340 (2625 3950);
PAINT GREEN (2625 3950);
DISPLAY INVISIBLE (2625 3950);
FORCEPROP 1 LAST HDL_TAP TRUE
J 0
(2950 3775);
DISPLAY 0.872340 (2950 3775);
DISPLAY INVISIBLE (2950 3775);
FORCEPROP 1 LAST PATH I170
J 0
(2623 3900);
DISPLAY 0.872340 (2623 3900);
PAINT GREEN (2623 3900);
DISPLAY INVISIBLE (2623 3900);
FORCEADD TAP..1
(2800 3750);
FORCEPROP 3 LASTPIN (2750 3750) SIG_NAME M_B_CPU0_SA_DQS_DN<8>
J 0
(2760 3760);
DISPLAY 0.659574 (2760 3760);
PAINT MONO (2760 3760);
DISPLAY INVISIBLE (2760 3760);
FORCEPROP 1 LASTPIN (2750 3750) BN 8
J 0
(2738 3758);
DISPLAY 0.680851 (2738 3758);
PAINT GREEN (2738 3758);
FORCEPROP 2 LAST CDS_LIB standard
J 0
(2800 3750);
DISPLAY INVISIBLE (2800 3750);
FORCEPROP 1 LAST BODY_TYPE PLUMBING
J 0
(2800 3800);
DISPLAY 0.872340 (2800 3800);
PAINT GREEN (2800 3800);
DISPLAY INVISIBLE (2800 3800);
FORCEPROP 1 LAST HDL_TAP TRUE
J 0
(3125 3625);
DISPLAY 0.872340 (3125 3625);
DISPLAY INVISIBLE (3125 3625);
FORCEPROP 1 LAST PATH I171
J 0
(2798 3750);
DISPLAY 0.872340 (2798 3750);
PAINT GREEN (2798 3750);
DISPLAY INVISIBLE (2798 3750);
FORCEADD TAP..1
(2800 3850);
FORCEPROP 3 LASTPIN (2750 3850) SIG_NAME M_B_CPU0_SA_DQS_DN<9>
J 0
(2760 3860);
DISPLAY 0.659574 (2760 3860);
PAINT MONO (2760 3860);
DISPLAY INVISIBLE (2760 3860);
FORCEPROP 1 LASTPIN (2750 3850) BN 9
J 0
(2738 3858);
DISPLAY 0.680851 (2738 3858);
PAINT GREEN (2738 3858);
FORCEPROP 2 LAST CDS_LIB standard
J 0
(2800 3850);
DISPLAY INVISIBLE (2800 3850);
FORCEPROP 1 LAST BODY_TYPE PLUMBING
J 0
(2800 3900);
DISPLAY 0.872340 (2800 3900);
PAINT GREEN (2800 3900);
DISPLAY INVISIBLE (2800 3900);
FORCEPROP 1 LAST HDL_TAP TRUE
J 0
(3125 3725);
DISPLAY 0.872340 (3125 3725);
DISPLAY INVISIBLE (3125 3725);
FORCEPROP 1 LAST PATH I172
J 0
(2798 3850);
DISPLAY 0.872340 (2798 3850);
PAINT GREEN (2798 3850);
DISPLAY INVISIBLE (2798 3850);
FORCEADD OFFPAGE..2
(3750 3875);
FORCEPROP 2 LAST $XR1 85 
J 0
(4029 3875);
DISPLAY 0.638298 (4029 3875);
PAINT MONO (4029 3875);
FORCEPROP 2 LAST $XR0 21 
J 0
(3939 3875);
DISPLAY 0.638298 (3939 3875);
PAINT MONO (3939 3875);
FORCEPROP 2 LAST CDS_LIB standard
J 0
(3750 3875);
PAINT MONO (3750 3875);
DISPLAY INVISIBLE (3750 3875);
FORCEPROP 1 LAST OFFPAGE TRUE
J 0
(4075 3750);
DISPLAY 1.170213 (4075 3750);
PAINT GREEN (4075 3750);
DISPLAY INVISIBLE (4075 3750);
FORCEPROP 1 LAST COMMENT_BODY TRUE
J 0
(3705 3780);
DISPLAY 1.170213 (3705 3780);
PAINT GREEN (3705 3780);
DISPLAY INVISIBLE (3705 3780);
FORCEPROP 2 LAST PATH I173
J 0
(3925 3950);
DISPLAY 1.021277 (3925 3950);
DISPLAY INVISIBLE (3925 3950);
FORCEADD OFFPAGE..2
(3750 3925);
FORCEPROP 2 LAST $XR1 85 
J 0
(4029 3925);
DISPLAY 0.638298 (4029 3925);
PAINT MONO (4029 3925);
FORCEPROP 2 LAST $XR0 21 
J 0
(3939 3925);
DISPLAY 0.638298 (3939 3925);
PAINT MONO (3939 3925);
FORCEPROP 2 LAST CDS_LIB standard
J 0
(3750 3925);
PAINT MONO (3750 3925);
DISPLAY INVISIBLE (3750 3925);
FORCEPROP 1 LAST OFFPAGE TRUE
J 0
(4075 3800);
DISPLAY 1.170213 (4075 3800);
PAINT GREEN (4075 3800);
DISPLAY INVISIBLE (4075 3800);
FORCEPROP 1 LAST COMMENT_BODY TRUE
J 0
(3705 3830);
DISPLAY 1.170213 (3705 3830);
PAINT GREEN (3705 3830);
DISPLAY INVISIBLE (3705 3830);
FORCEPROP 2 LAST PATH I174
J 0
(3925 4000);
DISPLAY 1.021277 (3925 4000);
DISPLAY INVISIBLE (3925 4000);
FORCEADD VCC_CORE..1
(4325 4450);
FORCEPROP 3 LASTPIN (4325 4400) SIG_NAME P12V_S3_AUX_CPU0_NVDIMM\g
J 0
(4335 4410);
DISPLAY 0.659574 (4335 4410);
PAINT MONO (4335 4410);
DISPLAY INVISIBLE (4335 4410);
FORCEPROP 1 LAST HDL_POWER P12V_S3_AUX_CPU0_NVDIMM
J 1
(4325 4500);
DISPLAY 1.148936 (4325 4500);
PAINT GREEN (4325 4500);
FORCEPROP 2 LAST CDS_LIB logical_power
J 0
(4325 4450);
PAINT MONO (4325 4450);
DISPLAY INVISIBLE (4325 4450);
FORCEPROP 1 LAST PATH I175
J 0
(4375 4475);
DISPLAY 0.872340 (4375 4475);
PAINT AQUA (4375 4475);
DISPLAY INVISIBLE (4375 4475);
FORCEADD UNIVERSAL_GND..1
(6025 200);
FORCEPROP 3 LASTPIN (6025 250) SIG_NAME GND\g
J 0
(6035 260);
DISPLAY 0.659574 (6035 260);
PAINT MONO (6035 260);
DISPLAY INVISIBLE (6035 260);
FORCEPROP 2 LAST CDS_LIB logical_power
J 0
(6025 200);
PAINT MONO (6025 200);
DISPLAY INVISIBLE (6025 200);
FORCEPROP 1 LAST HDL_POWER GND
J 1
(6050 125);
DISPLAY 0.872340 (6050 125);
PAINT GREEN (6050 125);
DISPLAY INVISIBLE (6050 125);
FORCEPROP 1 LAST PATH I176
J 0
(6100 200);
DISPLAY 0.872340 (6100 200);
PAINT AQUA (6100 200);
DISPLAY INVISIBLE (6100 200);
FORCEADD OFFPAGE..3
R 2
(-2675 1050);
FORCEPROP 2 LAST $XR0 114 
J 0
(-2955 1050);
DISPLAY 0.638298 (-2955 1050);
PAINT MONO (-2955 1050);
FORCEPROP 2 LAST CDS_LIB standard
J 0
(-2675 1050);
PAINT MONO (-2675 1050);
DISPLAY INVISIBLE (-2675 1050);
FORCEPROP 1 LAST OFFPAGE TRUE
J 2
(-3000 925);
DISPLAY 0.872340 (-3000 925);
DISPLAY INVISIBLE (-3000 925);
FORCEPROP 1 LAST COMMENT_BODY TRUE
J 2
(-2625 950);
DISPLAY 0.872340 (-2625 950);
PAINT GREEN (-2625 950);
DISPLAY INVISIBLE (-2625 950);
FORCEPROP 2 LAST PATH I177
J 0
(-2625 1125);
DISPLAY 1.021277 (-2625 1125);
DISPLAY INVISIBLE (-2625 1125);
FORCEADD SCONN288_ADR50017P130CC..3
(5175 2275);
FORCEPROP 1 LAST PART_NUMBER DFHST8FS461
J 0
(4720 4199);
DISPLAY 0.723404 (4720 4199);
PAINT GREEN (4720 4199);
DISPLAY INVISIBLE (4720 4199);
FORCEPROP 2 LAST VALUE SCONN288_ADR50017-P130CC
J 0
(4725 4400);
DISPLAY 1.021277 (4725 4400);
FORCEPROP 1 LAST MATERIAL IO
J 0
(4720 4072);
DISPLAY 0.723404 (4720 4072);
PAINT GREEN (4720 4072);
FORCEPROP 2 LAST PART_TYPE SMLF
J 0
(4725 4450);
DISPLAY 1.021277 (4725 4450);
FORCEPROP 1 LAST LOCATION J3
J 0
(4720 4346);
DISPLAY 0.723404 (4720 4346);
PAINT GREEN (4720 4346);
FORCEPROP 0 LASTPIN (5775 650) $PN G1
J 0
(5785 660);
DISPLAY 0.680851 (5785 660);
PAINT MONO (5785 660);
FORCEPROP 0 LASTPIN (5775 600) $PN G2
J 0
(5785 610);
DISPLAY 0.680851 (5785 610);
PAINT MONO (5785 610);
FORCEPROP 0 LASTPIN (5775 550) $PN G3
J 0
(5785 560);
DISPLAY 0.680851 (5785 560);
PAINT MONO (5785 560);
FORCEPROP 0 LASTPIN (4575 3800) $PN 1
J 2
(4565 3810);
DISPLAY 0.680851 (4565 3810);
PAINT MONO (4565 3810);
FORCEPROP 0 LASTPIN (4575 3850) $PN 145
J 2
(4565 3860);
DISPLAY 0.680851 (4565 3860);
PAINT MONO (4565 3860);
FORCEPROP 0 LASTPIN (4575 3900) $PN 146
J 2
(4565 3910);
DISPLAY 0.680851 (4565 3910);
PAINT MONO (4565 3910);
FORCEPROP 0 LASTPIN (5775 750) $PN 6
J 0
(5785 760);
DISPLAY 0.680851 (5785 760);
PAINT MONO (5785 760);
FORCEPROP 0 LASTPIN (5775 800) $PN 8
J 0
(5785 810);
DISPLAY 0.680851 (5785 810);
PAINT MONO (5785 810);
FORCEPROP 0 LASTPIN (5775 850) $PN 10
J 0
(5785 860);
DISPLAY 0.680851 (5785 860);
PAINT MONO (5785 860);
FORCEPROP 0 LASTPIN (5775 900) $PN 13
J 0
(5785 910);
DISPLAY 0.680851 (5785 910);
PAINT MONO (5785 910);
FORCEPROP 0 LASTPIN (5775 950) $PN 15
J 0
(5785 960);
DISPLAY 0.680851 (5785 960);
PAINT MONO (5785 960);
FORCEPROP 0 LASTPIN (5775 1000) $PN 17
J 0
(5785 1010);
DISPLAY 0.680851 (5785 1010);
PAINT MONO (5785 1010);
FORCEPROP 0 LASTPIN (5775 1050) $PN 19
J 0
(5785 1060);
DISPLAY 0.680851 (5785 1060);
PAINT MONO (5785 1060);
FORCEPROP 0 LASTPIN (5775 1100) $PN 21
J 0
(5785 1110);
DISPLAY 0.680851 (5785 1110);
PAINT MONO (5785 1110);
FORCEPROP 0 LASTPIN (5775 1150) $PN 24
J 0
(5785 1160);
DISPLAY 0.680851 (5785 1160);
PAINT MONO (5785 1160);
FORCEPROP 0 LASTPIN (5775 1200) $PN 26
J 0
(5785 1210);
DISPLAY 0.680851 (5785 1210);
PAINT MONO (5785 1210);
FORCEPROP 0 LASTPIN (5775 1250) $PN 28
J 0
(5785 1260);
DISPLAY 0.680851 (5785 1260);
PAINT MONO (5785 1260);
FORCEPROP 0 LASTPIN (5775 1300) $PN 30
J 0
(5785 1310);
DISPLAY 0.680851 (5785 1310);
PAINT MONO (5785 1310);
FORCEPROP 0 LASTPIN (5775 1350) $PN 32
J 0
(5785 1360);
DISPLAY 0.680851 (5785 1360);
PAINT MONO (5785 1360);
FORCEPROP 0 LASTPIN (5775 1400) $PN 35
J 0
(5785 1410);
DISPLAY 0.680851 (5785 1410);
PAINT MONO (5785 1410);
FORCEPROP 0 LASTPIN (5775 1450) $PN 37
J 0
(5785 1460);
DISPLAY 0.680851 (5785 1460);
PAINT MONO (5785 1460);
FORCEPROP 0 LASTPIN (5775 1500) $PN 39
J 0
(5785 1510);
DISPLAY 0.680851 (5785 1510);
PAINT MONO (5785 1510);
FORCEPROP 0 LASTPIN (5775 1550) $PN 41
J 0
(5785 1560);
DISPLAY 0.680851 (5785 1560);
PAINT MONO (5785 1560);
FORCEPROP 0 LASTPIN (5775 1600) $PN 43
J 0
(5785 1610);
DISPLAY 0.680851 (5785 1610);
PAINT MONO (5785 1610);
FORCEPROP 0 LASTPIN (5775 1650) $PN 46
J 0
(5785 1660);
DISPLAY 0.680851 (5785 1660);
PAINT MONO (5785 1660);
FORCEPROP 0 LASTPIN (5775 1700) $PN 48
J 0
(5785 1710);
DISPLAY 0.680851 (5785 1710);
PAINT MONO (5785 1710);
FORCEPROP 0 LASTPIN (5775 1750) $PN 50
J 0
(5785 1760);
DISPLAY 0.680851 (5785 1760);
PAINT MONO (5785 1760);
FORCEPROP 0 LASTPIN (5775 1800) $PN 52
J 0
(5785 1810);
DISPLAY 0.680851 (5785 1810);
PAINT MONO (5785 1810);
FORCEPROP 0 LASTPIN (5775 1850) $PN 54
J 0
(5785 1860);
DISPLAY 0.680851 (5785 1860);
PAINT MONO (5785 1860);
FORCEPROP 0 LASTPIN (5775 1900) $PN 57
J 0
(5785 1910);
DISPLAY 0.680851 (5785 1910);
PAINT MONO (5785 1910);
FORCEPROP 0 LASTPIN (5775 1950) $PN 59
J 0
(5785 1960);
DISPLAY 0.680851 (5785 1960);
PAINT MONO (5785 1960);
FORCEPROP 0 LASTPIN (5775 2000) $PN 61
J 0
(5785 2010);
DISPLAY 0.680851 (5785 2010);
PAINT MONO (5785 2010);
FORCEPROP 0 LASTPIN (5775 2050) $PN 63
J 0
(5785 2060);
DISPLAY 0.680851 (5785 2060);
PAINT MONO (5785 2060);
FORCEPROP 0 LASTPIN (5775 2100) $PN 65
J 0
(5785 2110);
DISPLAY 0.680851 (5785 2110);
PAINT MONO (5785 2110);
FORCEPROP 0 LASTPIN (5775 2150) $PN 67
J 0
(5785 2160);
DISPLAY 0.680851 (5785 2160);
PAINT MONO (5785 2160);
FORCEPROP 0 LASTPIN (5775 2200) $PN 69
J 0
(5785 2210);
DISPLAY 0.680851 (5785 2210);
PAINT MONO (5785 2210);
FORCEPROP 0 LASTPIN (5775 2250) $PN 71
J 0
(5785 2260);
DISPLAY 0.680851 (5785 2260);
PAINT MONO (5785 2260);
FORCEPROP 0 LASTPIN (5775 2300) $PN 73
J 0
(5785 2310);
DISPLAY 0.680851 (5785 2310);
PAINT MONO (5785 2310);
FORCEPROP 0 LASTPIN (5775 2350) $PN 75
J 0
(5785 2360);
DISPLAY 0.680851 (5785 2360);
PAINT MONO (5785 2360);
FORCEPROP 0 LASTPIN (5775 2400) $PN 77
J 0
(5785 2410);
DISPLAY 0.680851 (5785 2410);
PAINT MONO (5785 2410);
FORCEPROP 0 LASTPIN (5775 2450) $PN 79
J 0
(5785 2460);
DISPLAY 0.680851 (5785 2460);
PAINT MONO (5785 2460);
FORCEPROP 0 LASTPIN (5775 2500) $PN 81
J 0
(5785 2510);
DISPLAY 0.680851 (5785 2510);
PAINT MONO (5785 2510);
FORCEPROP 0 LASTPIN (5775 2550) $PN 83
J 0
(5785 2560);
DISPLAY 0.680851 (5785 2560);
PAINT MONO (5785 2560);
FORCEPROP 0 LASTPIN (5775 2600) $PN 85
J 0
(5785 2610);
DISPLAY 0.680851 (5785 2610);
PAINT MONO (5785 2610);
FORCEPROP 0 LASTPIN (5775 2650) $PN 88
J 0
(5785 2660);
DISPLAY 0.680851 (5785 2660);
PAINT MONO (5785 2660);
FORCEPROP 0 LASTPIN (5775 2700) $PN 90
J 0
(5785 2710);
DISPLAY 0.680851 (5785 2710);
PAINT MONO (5785 2710);
FORCEPROP 0 LASTPIN (5775 2750) $PN 92
J 0
(5785 2760);
DISPLAY 0.680851 (5785 2760);
PAINT MONO (5785 2760);
FORCEPROP 0 LASTPIN (5775 2800) $PN 95
J 0
(5785 2810);
DISPLAY 0.680851 (5785 2810);
PAINT MONO (5785 2810);
FORCEPROP 0 LASTPIN (5775 2850) $PN 97
J 0
(5785 2860);
DISPLAY 0.680851 (5785 2860);
PAINT MONO (5785 2860);
FORCEPROP 0 LASTPIN (5775 2900) $PN 99
J 0
(5785 2910);
DISPLAY 0.680851 (5785 2910);
PAINT MONO (5785 2910);
FORCEPROP 0 LASTPIN (5775 2950) $PN 101
J 0
(5785 2960);
DISPLAY 0.680851 (5785 2960);
PAINT MONO (5785 2960);
FORCEPROP 0 LASTPIN (5775 3000) $PN 103
J 0
(5785 3010);
DISPLAY 0.680851 (5785 3010);
PAINT MONO (5785 3010);
FORCEPROP 0 LASTPIN (5775 3050) $PN 106
J 0
(5785 3060);
DISPLAY 0.680851 (5785 3060);
PAINT MONO (5785 3060);
FORCEPROP 0 LASTPIN (5775 3100) $PN 108
J 0
(5785 3110);
DISPLAY 0.680851 (5785 3110);
PAINT MONO (5785 3110);
FORCEPROP 0 LASTPIN (5775 3150) $PN 110
J 0
(5785 3160);
DISPLAY 0.680851 (5785 3160);
PAINT MONO (5785 3160);
FORCEPROP 0 LASTPIN (5775 3200) $PN 112
J 0
(5785 3210);
DISPLAY 0.680851 (5785 3210);
PAINT MONO (5785 3210);
FORCEPROP 0 LASTPIN (5775 3250) $PN 114
J 0
(5785 3260);
DISPLAY 0.680851 (5785 3260);
PAINT MONO (5785 3260);
FORCEPROP 0 LASTPIN (5775 3300) $PN 117
J 0
(5785 3310);
DISPLAY 0.680851 (5785 3310);
PAINT MONO (5785 3310);
FORCEPROP 0 LASTPIN (5775 3350) $PN 119
J 0
(5785 3360);
DISPLAY 0.680851 (5785 3360);
PAINT MONO (5785 3360);
FORCEPROP 0 LASTPIN (5775 3400) $PN 121
J 0
(5785 3410);
DISPLAY 0.680851 (5785 3410);
PAINT MONO (5785 3410);
FORCEPROP 0 LASTPIN (5775 3450) $PN 123
J 0
(5785 3460);
DISPLAY 0.680851 (5785 3460);
PAINT MONO (5785 3460);
FORCEPROP 0 LASTPIN (5775 3500) $PN 125
J 0
(5785 3510);
DISPLAY 0.680851 (5785 3510);
PAINT MONO (5785 3510);
FORCEPROP 0 LASTPIN (5775 3550) $PN 128
J 0
(5785 3560);
DISPLAY 0.680851 (5785 3560);
PAINT MONO (5785 3560);
FORCEPROP 0 LASTPIN (5775 3600) $PN 130
J 0
(5785 3610);
DISPLAY 0.680851 (5785 3610);
PAINT MONO (5785 3610);
FORCEPROP 0 LASTPIN (5775 3650) $PN 132
J 0
(5785 3660);
DISPLAY 0.680851 (5785 3660);
PAINT MONO (5785 3660);
FORCEPROP 0 LASTPIN (5775 3700) $PN 134
J 0
(5785 3710);
DISPLAY 0.680851 (5785 3710);
PAINT MONO (5785 3710);
FORCEPROP 0 LASTPIN (5775 3750) $PN 136
J 0
(5785 3760);
DISPLAY 0.680851 (5785 3760);
PAINT MONO (5785 3760);
FORCEPROP 0 LASTPIN (5775 3800) $PN 139
J 0
(5785 3810);
DISPLAY 0.680851 (5785 3810);
PAINT MONO (5785 3810);
FORCEPROP 0 LASTPIN (5775 3850) $PN 141
J 0
(5785 3860);
DISPLAY 0.680851 (5785 3860);
PAINT MONO (5785 3860);
FORCEPROP 0 LASTPIN (5775 3900) $PN 143
J 0
(5785 3910);
DISPLAY 0.680851 (5785 3910);
PAINT MONO (5785 3910);
FORCEPROP 0 LASTPIN (4575 650) $PN 151
J 2
(4565 660);
DISPLAY 0.680851 (4565 660);
PAINT MONO (4565 660);
FORCEPROP 0 LASTPIN (4575 700) $PN 153
J 2
(4565 710);
DISPLAY 0.680851 (4565 710);
PAINT MONO (4565 710);
FORCEPROP 0 LASTPIN (4575 750) $PN 155
J 2
(4565 760);
DISPLAY 0.680851 (4565 760);
PAINT MONO (4565 760);
FORCEPROP 0 LASTPIN (4575 800) $PN 158
J 2
(4565 810);
DISPLAY 0.680851 (4565 810);
PAINT MONO (4565 810);
FORCEPROP 0 LASTPIN (4575 850) $PN 160
J 2
(4565 860);
DISPLAY 0.680851 (4565 860);
PAINT MONO (4565 860);
FORCEPROP 0 LASTPIN (4575 900) $PN 162
J 2
(4565 910);
DISPLAY 0.680851 (4565 910);
PAINT MONO (4565 910);
FORCEPROP 0 LASTPIN (4575 950) $PN 164
J 2
(4565 960);
DISPLAY 0.680851 (4565 960);
PAINT MONO (4565 960);
FORCEPROP 0 LASTPIN (4575 1000) $PN 166
J 2
(4565 1010);
DISPLAY 0.680851 (4565 1010);
PAINT MONO (4565 1010);
FORCEPROP 0 LASTPIN (4575 1050) $PN 169
J 2
(4565 1060);
DISPLAY 0.680851 (4565 1060);
PAINT MONO (4565 1060);
FORCEPROP 0 LASTPIN (4575 1100) $PN 171
J 2
(4565 1110);
DISPLAY 0.680851 (4565 1110);
PAINT MONO (4565 1110);
FORCEPROP 0 LASTPIN (4575 1150) $PN 173
J 2
(4565 1160);
DISPLAY 0.680851 (4565 1160);
PAINT MONO (4565 1160);
FORCEPROP 0 LASTPIN (4575 1200) $PN 175
J 2
(4565 1210);
DISPLAY 0.680851 (4565 1210);
PAINT MONO (4565 1210);
FORCEPROP 0 LASTPIN (4575 1250) $PN 177
J 2
(4565 1260);
DISPLAY 0.680851 (4565 1260);
PAINT MONO (4565 1260);
FORCEPROP 0 LASTPIN (4575 1300) $PN 180
J 2
(4565 1310);
DISPLAY 0.680851 (4565 1310);
PAINT MONO (4565 1310);
FORCEPROP 0 LASTPIN (4575 1350) $PN 182
J 2
(4565 1360);
DISPLAY 0.680851 (4565 1360);
PAINT MONO (4565 1360);
FORCEPROP 0 LASTPIN (4575 1400) $PN 184
J 2
(4565 1410);
DISPLAY 0.680851 (4565 1410);
PAINT MONO (4565 1410);
FORCEPROP 0 LASTPIN (4575 1450) $PN 186
J 2
(4565 1460);
DISPLAY 0.680851 (4565 1460);
PAINT MONO (4565 1460);
FORCEPROP 0 LASTPIN (4575 1500) $PN 188
J 2
(4565 1510);
DISPLAY 0.680851 (4565 1510);
PAINT MONO (4565 1510);
FORCEPROP 0 LASTPIN (4575 1550) $PN 191
J 2
(4565 1560);
DISPLAY 0.680851 (4565 1560);
PAINT MONO (4565 1560);
FORCEPROP 0 LASTPIN (4575 1600) $PN 193
J 2
(4565 1610);
DISPLAY 0.680851 (4565 1610);
PAINT MONO (4565 1610);
FORCEPROP 0 LASTPIN (4575 1650) $PN 195
J 2
(4565 1660);
DISPLAY 0.680851 (4565 1660);
PAINT MONO (4565 1660);
FORCEPROP 0 LASTPIN (4575 1700) $PN 197
J 2
(4565 1710);
DISPLAY 0.680851 (4565 1710);
PAINT MONO (4565 1710);
FORCEPROP 0 LASTPIN (4575 1750) $PN 199
J 2
(4565 1760);
DISPLAY 0.680851 (4565 1760);
PAINT MONO (4565 1760);
FORCEPROP 0 LASTPIN (4575 1800) $PN 202
J 2
(4565 1810);
DISPLAY 0.680851 (4565 1810);
PAINT MONO (4565 1810);
FORCEPROP 0 LASTPIN (4575 1850) $PN 204
J 2
(4565 1860);
DISPLAY 0.680851 (4565 1860);
PAINT MONO (4565 1860);
FORCEPROP 0 LASTPIN (4575 1900) $PN 206
J 2
(4565 1910);
DISPLAY 0.680851 (4565 1910);
PAINT MONO (4565 1910);
FORCEPROP 0 LASTPIN (4575 1950) $PN 208
J 2
(4565 1960);
DISPLAY 0.680851 (4565 1960);
PAINT MONO (4565 1960);
FORCEPROP 0 LASTPIN (4575 2000) $PN 210
J 2
(4565 2010);
DISPLAY 0.680851 (4565 2010);
PAINT MONO (4565 2010);
FORCEPROP 0 LASTPIN (4575 2050) $PN 212
J 2
(4565 2060);
DISPLAY 0.680851 (4565 2060);
PAINT MONO (4565 2060);
FORCEPROP 0 LASTPIN (4575 2100) $PN 214
J 2
(4565 2110);
DISPLAY 0.680851 (4565 2110);
PAINT MONO (4565 2110);
FORCEPROP 0 LASTPIN (4575 2150) $PN 216
J 2
(4565 2160);
DISPLAY 0.680851 (4565 2160);
PAINT MONO (4565 2160);
FORCEPROP 0 LASTPIN (4575 2200) $PN 219
J 2
(4565 2210);
DISPLAY 0.680851 (4565 2210);
PAINT MONO (4565 2210);
FORCEPROP 0 LASTPIN (4575 2250) $PN 222
J 2
(4565 2260);
DISPLAY 0.680851 (4565 2260);
PAINT MONO (4565 2260);
FORCEPROP 0 LASTPIN (4575 2300) $PN 224
J 2
(4565 2310);
DISPLAY 0.680851 (4565 2310);
PAINT MONO (4565 2310);
FORCEPROP 0 LASTPIN (4575 2350) $PN 226
J 2
(4565 2360);
DISPLAY 0.680851 (4565 2360);
PAINT MONO (4565 2360);
FORCEPROP 0 LASTPIN (4575 2400) $PN 228
J 2
(4565 2410);
DISPLAY 0.680851 (4565 2410);
PAINT MONO (4565 2410);
FORCEPROP 0 LASTPIN (4575 2450) $PN 230
J 2
(4565 2460);
DISPLAY 0.680851 (4565 2460);
PAINT MONO (4565 2460);
FORCEPROP 0 LASTPIN (4575 2500) $PN 233
J 2
(4565 2510);
DISPLAY 0.680851 (4565 2510);
PAINT MONO (4565 2510);
FORCEPROP 0 LASTPIN (4575 2550) $PN 235
J 2
(4565 2560);
DISPLAY 0.680851 (4565 2560);
PAINT MONO (4565 2560);
FORCEPROP 0 LASTPIN (4575 2600) $PN 237
J 2
(4565 2610);
DISPLAY 0.680851 (4565 2610);
PAINT MONO (4565 2610);
FORCEPROP 0 LASTPIN (4575 2650) $PN 240
J 2
(4565 2660);
DISPLAY 0.680851 (4565 2660);
PAINT MONO (4565 2660);
FORCEPROP 0 LASTPIN (4575 2700) $PN 242
J 2
(4565 2710);
DISPLAY 0.680851 (4565 2710);
PAINT MONO (4565 2710);
FORCEPROP 0 LASTPIN (4575 2750) $PN 244
J 2
(4565 2760);
DISPLAY 0.680851 (4565 2760);
PAINT MONO (4565 2760);
FORCEPROP 0 LASTPIN (4575 2800) $PN 246
J 2
(4565 2810);
DISPLAY 0.680851 (4565 2810);
PAINT MONO (4565 2810);
FORCEPROP 0 LASTPIN (4575 2850) $PN 248
J 2
(4565 2860);
DISPLAY 0.680851 (4565 2860);
PAINT MONO (4565 2860);
FORCEPROP 0 LASTPIN (4575 2900) $PN 251
J 2
(4565 2910);
DISPLAY 0.680851 (4565 2910);
PAINT MONO (4565 2910);
FORCEPROP 0 LASTPIN (4575 2950) $PN 253
J 2
(4565 2960);
DISPLAY 0.680851 (4565 2960);
PAINT MONO (4565 2960);
FORCEPROP 0 LASTPIN (4575 3000) $PN 255
J 2
(4565 3010);
DISPLAY 0.680851 (4565 3010);
PAINT MONO (4565 3010);
FORCEPROP 0 LASTPIN (4575 3050) $PN 257
J 2
(4565 3060);
DISPLAY 0.680851 (4565 3060);
PAINT MONO (4565 3060);
FORCEPROP 0 LASTPIN (4575 3100) $PN 259
J 2
(4565 3110);
DISPLAY 0.680851 (4565 3110);
PAINT MONO (4565 3110);
FORCEPROP 0 LASTPIN (4575 3150) $PN 262
J 2
(4565 3160);
DISPLAY 0.680851 (4565 3160);
PAINT MONO (4565 3160);
FORCEPROP 0 LASTPIN (4575 3200) $PN 264
J 2
(4565 3210);
DISPLAY 0.680851 (4565 3210);
PAINT MONO (4565 3210);
FORCEPROP 0 LASTPIN (4575 3250) $PN 266
J 2
(4565 3260);
DISPLAY 0.680851 (4565 3260);
PAINT MONO (4565 3260);
FORCEPROP 0 LASTPIN (4575 3300) $PN 268
J 2
(4565 3310);
DISPLAY 0.680851 (4565 3310);
PAINT MONO (4565 3310);
FORCEPROP 0 LASTPIN (4575 3350) $PN 270
J 2
(4565 3360);
DISPLAY 0.680851 (4565 3360);
PAINT MONO (4565 3360);
FORCEPROP 0 LASTPIN (4575 3400) $PN 273
J 2
(4565 3410);
DISPLAY 0.680851 (4565 3410);
PAINT MONO (4565 3410);
FORCEPROP 0 LASTPIN (4575 3450) $PN 275
J 2
(4565 3460);
DISPLAY 0.680851 (4565 3460);
PAINT MONO (4565 3460);
FORCEPROP 0 LASTPIN (4575 3500) $PN 277
J 2
(4565 3510);
DISPLAY 0.680851 (4565 3510);
PAINT MONO (4565 3510);
FORCEPROP 0 LASTPIN (4575 3550) $PN 279
J 2
(4565 3560);
DISPLAY 0.680851 (4565 3560);
PAINT MONO (4565 3560);
FORCEPROP 0 LASTPIN (4575 3600) $PN 281
J 2
(4565 3610);
DISPLAY 0.680851 (4565 3610);
PAINT MONO (4565 3610);
FORCEPROP 0 LASTPIN (4575 3650) $PN 284
J 2
(4565 3660);
DISPLAY 0.680851 (4565 3660);
PAINT MONO (4565 3660);
FORCEPROP 0 LASTPIN (4575 3700) $PN 286
J 2
(4565 3710);
DISPLAY 0.680851 (4565 3710);
PAINT MONO (4565 3710);
FORCEPROP 0 LASTPIN (4575 3750) $PN 288
J 2
(4565 3760);
DISPLAY 0.680851 (4565 3760);
PAINT MONO (4565 3760);
FORCEPROP 1 LAST NEEDS_NO_SIZE TRUE
J 0
(5175 2275);
DISPLAY 0.723404 (5175 2275);
PAINT GREEN (5175 2275);
DISPLAY INVISIBLE (5175 2275);
FORCEPROP 1 LAST CDS_LMAN_SYM_OUTLINE -450,1775,450,-1775
J 0
(5175 2275);
DISPLAY 0.468085 (5175 2275);
PAINT GREEN (5175 2275);
DISPLAY INVISIBLE (5175 2275);
FORCEPROP 2 LAST CDS_LIB pure_quanta
J 0
(5175 2275);
DISPLAY INVISIBLE (5175 2275);
FORCEPROP 0 LAST $SEC 3
J 0
(4725 4500);
DISPLAY 0.680851 (4725 4500);
PAINT MONO (4725 4500);
DISPLAY INVISIBLE (4725 4500);
FORCEPROP 0 LAST CDS_SEC 3
J 0
(4725 4500);
DISPLAY 1.021277 (4725 4500);
DISPLAY INVISIBLE (4725 4500);
FORCEPROP 1 LAST PATH I178
J 0
(5175 2275);
DISPLAY 0.723404 (5175 2275);
PAINT GREEN (5175 2275);
DISPLAY INVISIBLE (5175 2275);
FORCEADD SCONN288_ADR50017P130CC..2
(1725 2900);
FORCEPROP 1 LAST PART_NUMBER DFHST8FS461
J 0
(1132 4200);
DISPLAY 0.723404 (1132 4200);
PAINT GREEN (1132 4200);
DISPLAY INVISIBLE (1132 4200);
FORCEPROP 2 LAST VALUE SCONN288_ADR50017-P130CC
J 0
(1150 4400);
DISPLAY 1.021277 (1150 4400);
FORCEPROP 1 LAST MATERIAL IO
J 0
(1132 4073);
DISPLAY 0.723404 (1132 4073);
PAINT GREEN (1132 4073);
FORCEPROP 2 LAST PART_TYPE SMLF
J 0
(1150 4450);
DISPLAY 1.021277 (1150 4450);
FORCEPROP 1 LAST LOCATION J3
J 0
(1132 4347);
DISPLAY 0.723404 (1132 4347);
PAINT GREEN (1132 4347);
FORCEPROP 0 LASTPIN (2475 2950) $PN 12
J 0
(2485 2960);
DISPLAY 0.680851 (2485 2960);
PAINT MONO (2485 2960);
FORCEPROP 0 LASTPIN (2475 3000) $PN 11
J 0
(2485 3010);
DISPLAY 0.680851 (2485 3010);
PAINT MONO (2485 3010);
FORCEPROP 0 LASTPIN (2475 1900) $PN 105
J 0
(2485 1910);
DISPLAY 0.680851 (2485 1910);
PAINT MONO (2485 1910);
FORCEPROP 0 LASTPIN (2475 1950) $PN 104
J 0
(2485 1960);
DISPLAY 0.680851 (2485 1960);
PAINT MONO (2485 1960);
FORCEPROP 0 LASTPIN (2475 3050) $PN 23
J 0
(2485 3060);
DISPLAY 0.680851 (2485 3060);
PAINT MONO (2485 3060);
FORCEPROP 0 LASTPIN (2475 3100) $PN 22
J 0
(2485 3110);
DISPLAY 0.680851 (2485 3110);
PAINT MONO (2485 3110);
FORCEPROP 0 LASTPIN (2475 2000) $PN 116
J 0
(2485 2010);
DISPLAY 0.680851 (2485 2010);
PAINT MONO (2485 2010);
FORCEPROP 0 LASTPIN (2475 2050) $PN 115
J 0
(2485 2060);
DISPLAY 0.680851 (2485 2060);
PAINT MONO (2485 2060);
FORCEPROP 0 LASTPIN (2475 3150) $PN 34
J 0
(2485 3160);
DISPLAY 0.680851 (2485 3160);
PAINT MONO (2485 3160);
FORCEPROP 0 LASTPIN (2475 3200) $PN 33
J 0
(2485 3210);
DISPLAY 0.680851 (2485 3210);
PAINT MONO (2485 3210);
FORCEPROP 0 LASTPIN (2475 2100) $PN 127
J 0
(2485 2110);
DISPLAY 0.680851 (2485 2110);
PAINT MONO (2485 2110);
FORCEPROP 0 LASTPIN (2475 2150) $PN 126
J 0
(2485 2160);
DISPLAY 0.680851 (2485 2160);
PAINT MONO (2485 2160);
FORCEPROP 0 LASTPIN (2475 3250) $PN 45
J 0
(2485 3260);
DISPLAY 0.680851 (2485 3260);
PAINT MONO (2485 3260);
FORCEPROP 0 LASTPIN (2475 3300) $PN 44
J 0
(2485 3310);
DISPLAY 0.680851 (2485 3310);
PAINT MONO (2485 3310);
FORCEPROP 0 LASTPIN (2475 2200) $PN 138
J 0
(2485 2210);
DISPLAY 0.680851 (2485 2210);
PAINT MONO (2485 2210);
FORCEPROP 0 LASTPIN (2475 2250) $PN 137
J 0
(2485 2260);
DISPLAY 0.680851 (2485 2260);
PAINT MONO (2485 2260);
FORCEPROP 0 LASTPIN (2475 3350) $PN 56
J 0
(2485 3360);
DISPLAY 0.680851 (2485 3360);
PAINT MONO (2485 3360);
FORCEPROP 0 LASTPIN (2475 3400) $PN 55
J 0
(2485 3410);
DISPLAY 0.680851 (2485 3410);
PAINT MONO (2485 3410);
FORCEPROP 0 LASTPIN (2475 2300) $PN 238
J 0
(2485 2310);
DISPLAY 0.680851 (2485 2310);
PAINT MONO (2485 2310);
FORCEPROP 0 LASTPIN (2475 2350) $PN 239
J 0
(2485 2360);
DISPLAY 0.680851 (2485 2360);
PAINT MONO (2485 2360);
FORCEPROP 0 LASTPIN (2475 3450) $PN 156
J 0
(2485 3460);
DISPLAY 0.680851 (2485 3460);
PAINT MONO (2485 3460);
FORCEPROP 0 LASTPIN (2475 3500) $PN 157
J 0
(2485 3510);
DISPLAY 0.680851 (2485 3510);
PAINT MONO (2485 3510);
FORCEPROP 0 LASTPIN (2475 2400) $PN 249
J 0
(2485 2410);
DISPLAY 0.680851 (2485 2410);
PAINT MONO (2485 2410);
FORCEPROP 0 LASTPIN (2475 2450) $PN 250
J 0
(2485 2460);
DISPLAY 0.680851 (2485 2460);
PAINT MONO (2485 2460);
FORCEPROP 0 LASTPIN (2475 3550) $PN 167
J 0
(2485 3560);
DISPLAY 0.680851 (2485 3560);
PAINT MONO (2485 3560);
FORCEPROP 0 LASTPIN (2475 3600) $PN 168
J 0
(2485 3610);
DISPLAY 0.680851 (2485 3610);
PAINT MONO (2485 3610);
FORCEPROP 0 LASTPIN (2475 2500) $PN 260
J 0
(2485 2510);
DISPLAY 0.680851 (2485 2510);
PAINT MONO (2485 2510);
FORCEPROP 0 LASTPIN (2475 2550) $PN 261
J 0
(2485 2560);
DISPLAY 0.680851 (2485 2560);
PAINT MONO (2485 2560);
FORCEPROP 0 LASTPIN (2475 3650) $PN 178
J 0
(2485 3660);
DISPLAY 0.680851 (2485 3660);
PAINT MONO (2485 3660);
FORCEPROP 0 LASTPIN (2475 3700) $PN 179
J 0
(2485 3710);
DISPLAY 0.680851 (2485 3710);
PAINT MONO (2485 3710);
FORCEPROP 0 LASTPIN (2475 2600) $PN 271
J 0
(2485 2610);
DISPLAY 0.680851 (2485 2610);
PAINT MONO (2485 2610);
FORCEPROP 0 LASTPIN (2475 2650) $PN 272
J 0
(2485 2660);
DISPLAY 0.680851 (2485 2660);
PAINT MONO (2485 2660);
FORCEPROP 0 LASTPIN (2475 3750) $PN 189
J 0
(2485 3760);
DISPLAY 0.680851 (2485 3760);
PAINT MONO (2485 3760);
FORCEPROP 0 LASTPIN (2475 3800) $PN 190
J 0
(2485 3810);
DISPLAY 0.680851 (2485 3810);
PAINT MONO (2485 3810);
FORCEPROP 0 LASTPIN (2475 2700) $PN 282
J 0
(2485 2710);
DISPLAY 0.680851 (2485 2710);
PAINT MONO (2485 2710);
FORCEPROP 0 LASTPIN (2475 2750) $PN 283
J 0
(2485 2760);
DISPLAY 0.680851 (2485 2760);
PAINT MONO (2485 2760);
FORCEPROP 0 LASTPIN (2475 3850) $PN 200
J 0
(2485 3860);
DISPLAY 0.680851 (2485 3860);
PAINT MONO (2485 3860);
FORCEPROP 0 LASTPIN (2475 3900) $PN 201
J 0
(2485 3910);
DISPLAY 0.680851 (2485 3910);
PAINT MONO (2485 3910);
FORCEPROP 0 LASTPIN (2475 2800) $PN 94
J 0
(2485 2810);
DISPLAY 0.680851 (2485 2810);
PAINT MONO (2485 2810);
FORCEPROP 0 LASTPIN (2475 2850) $PN 93
J 0
(2485 2860);
DISPLAY 0.680851 (2485 2860);
PAINT MONO (2485 2860);
FORCEPROP 1 LAST NEEDS_NO_SIZE TRUE
J 0
(1725 2900);
DISPLAY 0.723404 (1725 2900);
PAINT GREEN (1725 2900);
DISPLAY INVISIBLE (1725 2900);
FORCEPROP 1 LAST CDS_LMAN_SYM_OUTLINE -600,1150,600,-1150
J 0
(1725 2900);
DISPLAY 0.468085 (1725 2900);
PAINT GREEN (1725 2900);
DISPLAY INVISIBLE (1725 2900);
FORCEPROP 2 LAST CDS_LIB pure_quanta
J 0
(1725 2900);
DISPLAY INVISIBLE (1725 2900);
FORCEPROP 0 LAST $SEC 2
J 0
(1150 4500);
DISPLAY 0.680851 (1150 4500);
PAINT MONO (1150 4500);
DISPLAY INVISIBLE (1150 4500);
FORCEPROP 0 LAST CDS_SEC 2
J 0
(1150 4500);
DISPLAY 1.021277 (1150 4500);
DISPLAY INVISIBLE (1150 4500);
FORCEPROP 1 LAST PATH I179
J 0
(1725 2900);
DISPLAY 0.723404 (1725 2900);
PAINT GREEN (1725 2900);
DISPLAY INVISIBLE (1725 2900);
FORCEADD OFFPAGE..1
(-2675 2750);
FORCEPROP 2 LAST $XR0 21 
J 0
(-2896 2750);
DISPLAY 0.638298 (-2896 2750);
PAINT MONO (-2896 2750);
FORCEPROP 2 LAST CDS_LIB standard
J 0
(-2675 2750);
PAINT MONO (-2675 2750);
DISPLAY INVISIBLE (-2675 2750);
FORCEPROP 1 LAST OFFPAGE TRUE
J 0
(-2350 2625);
DISPLAY 0.872340 (-2350 2625);
DISPLAY INVISIBLE (-2350 2625);
FORCEPROP 1 LAST COMMENT_BODY TRUE
J 0
(-2550 2650);
DISPLAY 0.872340 (-2550 2650);
PAINT GREEN (-2550 2650);
DISPLAY INVISIBLE (-2550 2650);
FORCEPROP 2 LAST PATH I18
J 0
(-2625 2825);
DISPLAY 1.021277 (-2625 2825);
DISPLAY INVISIBLE (-2625 2825);
FORCEADD SCONN288_ADR50017P130CC..1
(-925 2175);
FORCEPROP 1 LAST PART_NUMBER DFHST8FS461
J 0
(-1370 4197);
DISPLAY 0.723404 (-1370 4197);
PAINT GREEN (-1370 4197);
DISPLAY INVISIBLE (-1370 4197);
FORCEPROP 2 LAST VALUE SCONN288_ADR50017-P130CC
J 0
(-1350 4400);
DISPLAY 1.021277 (-1350 4400);
FORCEPROP 1 LAST MATERIAL IO
J 0
(-1370 4070);
DISPLAY 0.723404 (-1370 4070);
PAINT GREEN (-1370 4070);
FORCEPROP 2 LAST PART_TYPE SMLF
J 0
(-1350 4450);
DISPLAY 1.021277 (-1350 4450);
FORCEPROP 1 LAST LOCATION J3
J 0
(-1370 4344);
DISPLAY 0.723404 (-1370 4344);
PAINT GREEN (-1370 4344);
FORCEPROP 0 LASTPIN (-1525 1550) $PN 62
J 2
(-1535 1560);
DISPLAY 0.680851 (-1535 1560);
PAINT MONO (-1535 1560);
FORCEPROP 0 LASTPIN (-1525 3600) $PN 66
J 2
(-1535 3610);
DISPLAY 0.680851 (-1535 3610);
PAINT MONO (-1535 3610);
FORCEPROP 0 LASTPIN (-1525 3200) $PN 76
J 2
(-1535 3210);
DISPLAY 0.680851 (-1535 3210);
PAINT MONO (-1535 3210);
FORCEPROP 0 LASTPIN (-1525 3650) $PN 211
J 2
(-1535 3660);
DISPLAY 0.680851 (-1535 3660);
PAINT MONO (-1535 3660);
FORCEPROP 0 LASTPIN (-1525 3250) $PN 221
J 2
(-1535 3260);
DISPLAY 0.680851 (-1535 3260);
PAINT MONO (-1535 3260);
FORCEPROP 0 LASTPIN (-1525 3700) $PN 68
J 2
(-1535 3710);
DISPLAY 0.680851 (-1535 3710);
PAINT MONO (-1535 3710);
FORCEPROP 0 LASTPIN (-1525 3300) $PN 78
J 2
(-1535 3310);
DISPLAY 0.680851 (-1535 3310);
PAINT MONO (-1535 3310);
FORCEPROP 0 LASTPIN (-1525 3750) $PN 213
J 2
(-1535 3760);
DISPLAY 0.680851 (-1535 3760);
PAINT MONO (-1535 3760);
FORCEPROP 0 LASTPIN (-1525 3350) $PN 223
J 2
(-1535 3360);
DISPLAY 0.680851 (-1535 3360);
PAINT MONO (-1535 3360);
FORCEPROP 0 LASTPIN (-1525 3800) $PN 70
J 2
(-1535 3810);
DISPLAY 0.680851 (-1535 3810);
PAINT MONO (-1535 3810);
FORCEPROP 0 LASTPIN (-1525 3400) $PN 80
J 2
(-1535 3410);
DISPLAY 0.680851 (-1535 3410);
PAINT MONO (-1535 3410);
FORCEPROP 0 LASTPIN (-1525 3850) $PN 215
J 2
(-1535 3860);
DISPLAY 0.680851 (-1535 3860);
PAINT MONO (-1535 3860);
FORCEPROP 0 LASTPIN (-1525 3450) $PN 225
J 2
(-1535 3460);
DISPLAY 0.680851 (-1535 3460);
PAINT MONO (-1535 3460);
FORCEPROP 0 LASTPIN (-1525 3900) $PN 72
J 2
(-1535 3910);
DISPLAY 0.680851 (-1535 3910);
PAINT MONO (-1535 3910);
FORCEPROP 0 LASTPIN (-1525 3500) $PN 82
J 2
(-1535 3510);
DISPLAY 0.680851 (-1535 3510);
PAINT MONO (-1535 3510);
FORCEPROP 0 LASTPIN (-1525 2150) $PN 51
J 2
(-1535 2160);
DISPLAY 0.680851 (-1535 2160);
PAINT MONO (-1535 2160);
FORCEPROP 0 LASTPIN (-1525 1700) $PN 96
J 2
(-1535 1710);
DISPLAY 0.680851 (-1535 1710);
PAINT MONO (-1535 1710);
FORCEPROP 0 LASTPIN (-1525 2200) $PN 53
J 2
(-1535 2210);
DISPLAY 0.680851 (-1535 2210);
PAINT MONO (-1535 2210);
FORCEPROP 0 LASTPIN (-1525 1750) $PN 98
J 2
(-1535 1760);
DISPLAY 0.680851 (-1535 1760);
PAINT MONO (-1535 1760);
FORCEPROP 0 LASTPIN (-1525 2250) $PN 196
J 2
(-1535 2260);
DISPLAY 0.680851 (-1535 2260);
PAINT MONO (-1535 2260);
FORCEPROP 0 LASTPIN (-1525 1800) $PN 241
J 2
(-1535 1810);
DISPLAY 0.680851 (-1535 1810);
PAINT MONO (-1535 1810);
FORCEPROP 0 LASTPIN (-1525 2300) $PN 198
J 2
(-1535 2310);
DISPLAY 0.680851 (-1535 2310);
PAINT MONO (-1535 2310);
FORCEPROP 0 LASTPIN (-1525 1850) $PN 243
J 2
(-1535 1860);
DISPLAY 0.680851 (-1535 1860);
PAINT MONO (-1535 1860);
FORCEPROP 0 LASTPIN (-1525 2350) $PN 58
J 2
(-1535 2360);
DISPLAY 0.680851 (-1535 2360);
PAINT MONO (-1535 2360);
FORCEPROP 0 LASTPIN (-1525 1900) $PN 89
J 2
(-1535 1910);
DISPLAY 0.680851 (-1535 1910);
PAINT MONO (-1535 1910);
FORCEPROP 0 LASTPIN (-1525 2400) $PN 60
J 2
(-1535 2410);
DISPLAY 0.680851 (-1535 2410);
PAINT MONO (-1535 2410);
FORCEPROP 0 LASTPIN (-1525 1950) $PN 91
J 2
(-1535 1960);
DISPLAY 0.680851 (-1535 1960);
PAINT MONO (-1535 1960);
FORCEPROP 0 LASTPIN (-1525 2450) $PN 203
J 2
(-1535 2460);
DISPLAY 0.680851 (-1535 2460);
PAINT MONO (-1535 2460);
FORCEPROP 0 LASTPIN (-1525 2000) $PN 234
J 2
(-1535 2010);
DISPLAY 0.680851 (-1535 2010);
PAINT MONO (-1535 2010);
FORCEPROP 0 LASTPIN (-1525 2500) $PN 205
J 2
(-1535 2510);
DISPLAY 0.680851 (-1535 2510);
PAINT MONO (-1535 2510);
FORCEPROP 0 LASTPIN (-1525 2050) $PN 236
J 2
(-1535 2060);
DISPLAY 0.680851 (-1535 2060);
PAINT MONO (-1535 2060);
FORCEPROP 0 LASTPIN (-1525 2600) $PN 218
J 2
(-1535 2610);
DISPLAY 0.680851 (-1535 2610);
PAINT MONO (-1535 2610);
FORCEPROP 0 LASTPIN (-1525 2650) $PN 217
J 2
(-1535 2660);
DISPLAY 0.680851 (-1535 2660);
PAINT MONO (-1535 2660);
FORCEPROP 0 LASTPIN (-1525 2900) $PN 64
J 2
(-1535 2910);
DISPLAY 0.680851 (-1535 2910);
PAINT MONO (-1535 2910);
FORCEPROP 0 LASTPIN (-1525 2750) $PN 84
J 2
(-1535 2760);
DISPLAY 0.680851 (-1535 2760);
PAINT MONO (-1535 2760);
FORCEPROP 0 LASTPIN (-1525 2950) $PN 209
J 2
(-1535 2960);
DISPLAY 0.680851 (-1535 2960);
PAINT MONO (-1535 2960);
FORCEPROP 0 LASTPIN (-1525 2800) $PN 229
J 2
(-1535 2810);
DISPLAY 0.680851 (-1535 2810);
PAINT MONO (-1535 2810);
FORCEPROP 0 LASTPIN (-325 2350) $PN 7
J 0
(-315 2360);
DISPLAY 0.680851 (-315 2360);
PAINT MONO (-315 2360);
FORCEPROP 0 LASTPIN (-325 700) $PN 100
J 0
(-315 710);
DISPLAY 0.680851 (-315 710);
PAINT MONO (-315 710);
FORCEPROP 0 LASTPIN (-325 2400) $PN 9
J 0
(-315 2410);
DISPLAY 0.680851 (-315 2410);
PAINT MONO (-315 2410);
FORCEPROP 0 LASTPIN (-325 750) $PN 102
J 0
(-315 760);
DISPLAY 0.680851 (-315 760);
PAINT MONO (-315 760);
FORCEPROP 0 LASTPIN (-325 2450) $PN 152
J 0
(-315 2460);
DISPLAY 0.680851 (-315 2460);
PAINT MONO (-315 2460);
FORCEPROP 0 LASTPIN (-325 800) $PN 245
J 0
(-315 810);
DISPLAY 0.680851 (-315 810);
PAINT MONO (-315 810);
FORCEPROP 0 LASTPIN (-325 2500) $PN 154
J 0
(-315 2510);
DISPLAY 0.680851 (-315 2510);
PAINT MONO (-315 2510);
FORCEPROP 0 LASTPIN (-325 850) $PN 247
J 0
(-315 860);
DISPLAY 0.680851 (-315 860);
PAINT MONO (-315 860);
FORCEPROP 0 LASTPIN (-325 2550) $PN 14
J 0
(-315 2560);
DISPLAY 0.680851 (-315 2560);
PAINT MONO (-315 2560);
FORCEPROP 0 LASTPIN (-325 900) $PN 107
J 0
(-315 910);
DISPLAY 0.680851 (-315 910);
PAINT MONO (-315 910);
FORCEPROP 0 LASTPIN (-325 2600) $PN 16
J 0
(-315 2610);
DISPLAY 0.680851 (-315 2610);
PAINT MONO (-315 2610);
FORCEPROP 0 LASTPIN (-325 950) $PN 109
J 0
(-315 960);
DISPLAY 0.680851 (-315 960);
PAINT MONO (-315 960);
FORCEPROP 0 LASTPIN (-325 2650) $PN 159
J 0
(-315 2660);
DISPLAY 0.680851 (-315 2660);
PAINT MONO (-315 2660);
FORCEPROP 0 LASTPIN (-325 1000) $PN 252
J 0
(-315 1010);
DISPLAY 0.680851 (-315 1010);
PAINT MONO (-315 1010);
FORCEPROP 0 LASTPIN (-325 2700) $PN 161
J 0
(-315 2710);
DISPLAY 0.680851 (-315 2710);
PAINT MONO (-315 2710);
FORCEPROP 0 LASTPIN (-325 1050) $PN 254
J 0
(-315 1060);
DISPLAY 0.680851 (-315 1060);
PAINT MONO (-315 1060);
FORCEPROP 0 LASTPIN (-325 2750) $PN 18
J 0
(-315 2760);
DISPLAY 0.680851 (-315 2760);
PAINT MONO (-315 2760);
FORCEPROP 0 LASTPIN (-325 1100) $PN 111
J 0
(-315 1110);
DISPLAY 0.680851 (-315 1110);
PAINT MONO (-315 1110);
FORCEPROP 0 LASTPIN (-325 2800) $PN 20
J 0
(-315 2810);
DISPLAY 0.680851 (-315 2810);
PAINT MONO (-315 2810);
FORCEPROP 0 LASTPIN (-325 1150) $PN 113
J 0
(-315 1160);
DISPLAY 0.680851 (-315 1160);
PAINT MONO (-315 1160);
FORCEPROP 0 LASTPIN (-325 2850) $PN 163
J 0
(-315 2860);
DISPLAY 0.680851 (-315 2860);
PAINT MONO (-315 2860);
FORCEPROP 0 LASTPIN (-325 1200) $PN 256
J 0
(-315 1210);
DISPLAY 0.680851 (-315 1210);
PAINT MONO (-315 1210);
FORCEPROP 0 LASTPIN (-325 2900) $PN 165
J 0
(-315 2910);
DISPLAY 0.680851 (-315 2910);
PAINT MONO (-315 2910);
FORCEPROP 0 LASTPIN (-325 1250) $PN 258
J 0
(-315 1260);
DISPLAY 0.680851 (-315 1260);
PAINT MONO (-315 1260);
FORCEPROP 0 LASTPIN (-325 2950) $PN 25
J 0
(-315 2960);
DISPLAY 0.680851 (-315 2960);
PAINT MONO (-315 2960);
FORCEPROP 0 LASTPIN (-325 1300) $PN 118
J 0
(-315 1310);
DISPLAY 0.680851 (-315 1310);
PAINT MONO (-315 1310);
FORCEPROP 0 LASTPIN (-325 3000) $PN 27
J 0
(-315 3010);
DISPLAY 0.680851 (-315 3010);
PAINT MONO (-315 3010);
FORCEPROP 0 LASTPIN (-325 1350) $PN 120
J 0
(-315 1360);
DISPLAY 0.680851 (-315 1360);
PAINT MONO (-315 1360);
FORCEPROP 0 LASTPIN (-325 3050) $PN 170
J 0
(-315 3060);
DISPLAY 0.680851 (-315 3060);
PAINT MONO (-315 3060);
FORCEPROP 0 LASTPIN (-325 1400) $PN 263
J 0
(-315 1410);
DISPLAY 0.680851 (-315 1410);
PAINT MONO (-315 1410);
FORCEPROP 0 LASTPIN (-325 3100) $PN 172
J 0
(-315 3110);
DISPLAY 0.680851 (-315 3110);
PAINT MONO (-315 3110);
FORCEPROP 0 LASTPIN (-325 1450) $PN 265
J 0
(-315 1460);
DISPLAY 0.680851 (-315 1460);
PAINT MONO (-315 1460);
FORCEPROP 0 LASTPIN (-325 3150) $PN 29
J 0
(-315 3160);
DISPLAY 0.680851 (-315 3160);
PAINT MONO (-315 3160);
FORCEPROP 0 LASTPIN (-325 1500) $PN 122
J 0
(-315 1510);
DISPLAY 0.680851 (-315 1510);
PAINT MONO (-315 1510);
FORCEPROP 0 LASTPIN (-325 3200) $PN 31
J 0
(-315 3210);
DISPLAY 0.680851 (-315 3210);
PAINT MONO (-315 3210);
FORCEPROP 0 LASTPIN (-325 1550) $PN 124
J 0
(-315 1560);
DISPLAY 0.680851 (-315 1560);
PAINT MONO (-315 1560);
FORCEPROP 0 LASTPIN (-325 3250) $PN 174
J 0
(-315 3260);
DISPLAY 0.680851 (-315 3260);
PAINT MONO (-315 3260);
FORCEPROP 0 LASTPIN (-325 1600) $PN 267
J 0
(-315 1610);
DISPLAY 0.680851 (-315 1610);
PAINT MONO (-315 1610);
FORCEPROP 0 LASTPIN (-325 3300) $PN 176
J 0
(-315 3310);
DISPLAY 0.680851 (-315 3310);
PAINT MONO (-315 3310);
FORCEPROP 0 LASTPIN (-325 1650) $PN 269
J 0
(-315 1660);
DISPLAY 0.680851 (-315 1660);
PAINT MONO (-315 1660);
FORCEPROP 0 LASTPIN (-325 3350) $PN 36
J 0
(-315 3360);
DISPLAY 0.680851 (-315 3360);
PAINT MONO (-315 3360);
FORCEPROP 0 LASTPIN (-325 1700) $PN 129
J 0
(-315 1710);
DISPLAY 0.680851 (-315 1710);
PAINT MONO (-315 1710);
FORCEPROP 0 LASTPIN (-325 3400) $PN 38
J 0
(-315 3410);
DISPLAY 0.680851 (-315 3410);
PAINT MONO (-315 3410);
FORCEPROP 0 LASTPIN (-325 1750) $PN 131
J 0
(-315 1760);
DISPLAY 0.680851 (-315 1760);
PAINT MONO (-315 1760);
FORCEPROP 0 LASTPIN (-325 3450) $PN 181
J 0
(-315 3460);
DISPLAY 0.680851 (-315 3460);
PAINT MONO (-315 3460);
FORCEPROP 0 LASTPIN (-325 1800) $PN 274
J 0
(-315 1810);
DISPLAY 0.680851 (-315 1810);
PAINT MONO (-315 1810);
FORCEPROP 0 LASTPIN (-325 3500) $PN 183
J 0
(-315 3510);
DISPLAY 0.680851 (-315 3510);
PAINT MONO (-315 3510);
FORCEPROP 0 LASTPIN (-325 1850) $PN 276
J 0
(-315 1860);
DISPLAY 0.680851 (-315 1860);
PAINT MONO (-315 1860);
FORCEPROP 0 LASTPIN (-325 3550) $PN 40
J 0
(-315 3560);
DISPLAY 0.680851 (-315 3560);
PAINT MONO (-315 3560);
FORCEPROP 0 LASTPIN (-325 1900) $PN 133
J 0
(-315 1910);
DISPLAY 0.680851 (-315 1910);
PAINT MONO (-315 1910);
FORCEPROP 0 LASTPIN (-325 3600) $PN 42
J 0
(-315 3610);
DISPLAY 0.680851 (-315 3610);
PAINT MONO (-315 3610);
FORCEPROP 0 LASTPIN (-325 1950) $PN 135
J 0
(-315 1960);
DISPLAY 0.680851 (-315 1960);
PAINT MONO (-315 1960);
FORCEPROP 0 LASTPIN (-325 3650) $PN 185
J 0
(-315 3660);
DISPLAY 0.680851 (-315 3660);
PAINT MONO (-315 3660);
FORCEPROP 0 LASTPIN (-325 2000) $PN 278
J 0
(-315 2010);
DISPLAY 0.680851 (-315 2010);
PAINT MONO (-315 2010);
FORCEPROP 0 LASTPIN (-325 3700) $PN 187
J 0
(-315 3710);
DISPLAY 0.680851 (-315 3710);
PAINT MONO (-315 3710);
FORCEPROP 0 LASTPIN (-325 2050) $PN 280
J 0
(-315 2060);
DISPLAY 0.680851 (-315 2060);
PAINT MONO (-315 2060);
FORCEPROP 0 LASTPIN (-325 3750) $PN 47
J 0
(-315 3760);
DISPLAY 0.680851 (-315 3760);
PAINT MONO (-315 3760);
FORCEPROP 0 LASTPIN (-325 2100) $PN 140
J 0
(-315 2110);
DISPLAY 0.680851 (-315 2110);
PAINT MONO (-315 2110);
FORCEPROP 0 LASTPIN (-325 3800) $PN 49
J 0
(-315 3810);
DISPLAY 0.680851 (-315 3810);
PAINT MONO (-315 3810);
FORCEPROP 0 LASTPIN (-325 2150) $PN 142
J 0
(-315 2160);
DISPLAY 0.680851 (-315 2160);
PAINT MONO (-315 2160);
FORCEPROP 0 LASTPIN (-325 3850) $PN 192
J 0
(-315 3860);
DISPLAY 0.680851 (-315 3860);
PAINT MONO (-315 3860);
FORCEPROP 0 LASTPIN (-325 2200) $PN 285
J 0
(-315 2210);
DISPLAY 0.680851 (-315 2210);
PAINT MONO (-315 2210);
FORCEPROP 0 LASTPIN (-325 3900) $PN 194
J 0
(-315 3910);
DISPLAY 0.680851 (-315 3910);
PAINT MONO (-315 3910);
FORCEPROP 0 LASTPIN (-325 2250) $PN 287
J 0
(-315 2260);
DISPLAY 0.680851 (-315 2260);
PAINT MONO (-315 2260);
FORCEPROP 0 LASTPIN (-1525 1400) $PN 148
J 2
(-1535 1410);
DISPLAY 0.680851 (-1535 1410);
PAINT MONO (-1535 1410);
FORCEPROP 0 LASTPIN (-1525 1300) $PN 4
J 2
(-1535 1310);
DISPLAY 0.680851 (-1535 1310);
PAINT MONO (-1535 1310);
FORCEPROP 0 LASTPIN (-1525 1350) $PN 5
J 2
(-1535 1360);
DISPLAY 0.680851 (-1535 1360);
PAINT MONO (-1535 1360);
FORCEPROP 0 LASTPIN (-1525 500) $PN 86
J 2
(-1535 510);
DISPLAY 0.680851 (-1535 510);
PAINT MONO (-1535 510);
FORCEPROP 0 LASTPIN (-1525 450) $PN 87
J 2
(-1535 460);
DISPLAY 0.680851 (-1535 460);
PAINT MONO (-1535 460);
FORCEPROP 0 LASTPIN (-1525 3100) $PN 74
J 2
(-1535 3110);
DISPLAY 0.680851 (-1535 3110);
PAINT MONO (-1535 3110);
FORCEPROP 0 LASTPIN (-1525 3050) $PN 227
J 2
(-1535 3060);
DISPLAY 0.680851 (-1535 3060);
PAINT MONO (-1535 3060);
FORCEPROP 0 LASTPIN (-1525 1050) $PN 147
J 2
(-1535 1060);
DISPLAY 0.680851 (-1535 1060);
PAINT MONO (-1535 1060);
FORCEPROP 0 LASTPIN (-1525 1600) $PN 207
J 2
(-1535 1610);
DISPLAY 0.680851 (-1535 1610);
PAINT MONO (-1535 1610);
FORCEPROP 0 LASTPIN (-1525 650) $PN 2
J 2
(-1535 660);
DISPLAY 0.680851 (-1535 660);
PAINT MONO (-1535 660);
FORCEPROP 0 LASTPIN (-1525 700) $PN 144
J 2
(-1535 710);
DISPLAY 0.680851 (-1535 710);
PAINT MONO (-1535 710);
FORCEPROP 0 LASTPIN (-1525 750) $PN 149
J 2
(-1535 760);
DISPLAY 0.680851 (-1535 760);
PAINT MONO (-1535 760);
FORCEPROP 0 LASTPIN (-1525 800) $PN 150
J 2
(-1535 810);
DISPLAY 0.680851 (-1535 810);
PAINT MONO (-1535 810);
FORCEPROP 0 LASTPIN (-1525 850) $PN 220
J 2
(-1535 860);
DISPLAY 0.680851 (-1535 860);
PAINT MONO (-1535 860);
FORCEPROP 0 LASTPIN (-1525 900) $PN 231
J 2
(-1535 910);
DISPLAY 0.680851 (-1535 910);
PAINT MONO (-1535 910);
FORCEPROP 0 LASTPIN (-1525 950) $PN 232
J 2
(-1535 960);
DISPLAY 0.680851 (-1535 960);
PAINT MONO (-1535 960);
FORCEPROP 0 LASTPIN (-1525 1450) $PN 3
J 2
(-1535 1460);
DISPLAY 0.680851 (-1535 1460);
PAINT MONO (-1535 1460);
FORCEPROP 1 LAST NEEDS_NO_SIZE TRUE
J 0
(-925 2175);
DISPLAY 0.723404 (-925 2175);
PAINT GREEN (-925 2175);
DISPLAY INVISIBLE (-925 2175);
FORCEPROP 1 LAST CDS_LMAN_SYM_OUTLINE -450,1875,450,-1875
J 0
(-925 2175);
DISPLAY 0.468085 (-925 2175);
PAINT GREEN (-925 2175);
DISPLAY INVISIBLE (-925 2175);
FORCEPROP 2 LAST CDS_LIB pure_quanta
J 0
(-925 2175);
DISPLAY INVISIBLE (-925 2175);
FORCEPROP 0 LAST $SEC 1
J 0
(-1350 4500);
DISPLAY 0.680851 (-1350 4500);
PAINT MONO (-1350 4500);
DISPLAY INVISIBLE (-1350 4500);
FORCEPROP 0 LAST CDS_SEC 1
J 0
(-1350 4500);
DISPLAY 1.021277 (-1350 4500);
DISPLAY INVISIBLE (-1350 4500);
FORCEPROP 1 LAST PATH I180
J 0
(-925 2175);
DISPLAY 0.723404 (-925 2175);
PAINT GREEN (-925 2175);
DISPLAY INVISIBLE (-925 2175);
FORCEADD Q_RES..1
(-2800 1200);
FORCEPROP 1 LAST PART_NUMBER CS04992FB07
J 0
(-2700 1175);
DISPLAY 0.404255 (-2700 1175);
DISPLAY INVISIBLE (-2700 1175);
FORCEPROP 1 LAST VALUE 49.9
J 2
(-2575 1200);
DISPLAY 0.510638 (-2575 1200);
FORCEPROP 1 LAST MATERIAL CHIP
J 0
(-2950 1175);
DISPLAY 0.404255 (-2950 1175);
FORCEPROP 1 LAST $LOCATION R3877
J 0
(-3050 1200);
DISPLAY 0.638298 (-3050 1200);
FORCEPROP 1 LASTPIN (-2900 1200) $PN 1
J 0
(-2888 1212);
DISPLAY 0.787234 (-2888 1212);
PAINT MONO (-2888 1212);
FORCEPROP 1 LASTPIN (-2700 1200) $PN 2
J 0
(-2738 1212);
DISPLAY 0.787234 (-2738 1212);
PAINT MONO (-2738 1212);
FORCEPROP 2 LAST CDS_LIB pure_quanta
J 0
(-2800 1200);
DISPLAY INVISIBLE (-2800 1200);
FORCEPROP 1 LAST PACK_TYPE 0402LF
J 0
(-2500 1200);
DISPLAY 0.510638 (-2500 1200);
DISPLAY INVISIBLE (-2500 1200);
FORCEPROP 1 LAST TOLERANCE 1%
J 0
(-2575 1200);
DISPLAY 0.510638 (-2575 1200);
DISPLAY INVISIBLE (-2575 1200);
FORCEPROP 1 LAST WATTAGE 1/16W
J 2
(-2500 1150);
DISPLAY 0.404255 (-2500 1150);
DISPLAY INVISIBLE (-2500 1150);
FORCEPROP 0 LAST CDS_LOCATION R3877
J 0
(-2925 1250);
DISPLAY 1.021277 (-2925 1250);
DISPLAY INVISIBLE (-2925 1250);
FORCEPROP 0 LAST $SEC 1
J 0
(-2925 1250);
DISPLAY 0.680851 (-2925 1250);
PAINT MONO (-2925 1250);
DISPLAY INVISIBLE (-2925 1250);
FORCEPROP 0 LAST CDS_SEC 1
J 0
(-2925 1250);
DISPLAY 1.021277 (-2925 1250);
DISPLAY INVISIBLE (-2925 1250);
FORCEPROP 1 LAST PATH I182
J 0
(-2850 1350);
DISPLAY 0.978723 (-2850 1350);
PAINT WHITE (-2850 1350);
DISPLAY INVISIBLE (-2850 1350);
FORCEADD OFFPAGE..1
(-1550 1150);
FORCEPROP 2 LAST $XR7 89 
J 0
(-2432 1150);
DISPLAY 0.638298 (-2432 1150);
PAINT MONO (-2432 1150);
FORCEPROP 2 LAST $XR6 88 
J 0
(-2342 1150);
DISPLAY 0.638298 (-2342 1150);
PAINT MONO (-2342 1150);
FORCEPROP 2 LAST $XR5 87 
J 0
(-2252 1150);
DISPLAY 0.638298 (-2252 1150);
PAINT MONO (-2252 1150);
FORCEPROP 2 LAST $XR4 86 
J 0
(-2162 1150);
DISPLAY 0.638298 (-2162 1150);
PAINT MONO (-2162 1150);
FORCEPROP 2 LAST $XR3 85 
J 0
(-2072 1150);
DISPLAY 0.638298 (-2072 1150);
PAINT MONO (-2072 1150);
FORCEPROP 2 LAST $XR2 83 
J 0
(-1982 1150);
DISPLAY 0.638298 (-1982 1150);
PAINT MONO (-1982 1150);
FORCEPROP 2 LAST $XR1 82 
J 0
(-1892 1150);
DISPLAY 0.638298 (-1892 1150);
PAINT MONO (-1892 1150);
FORCEPROP 2 LAST $XR0 229 
J 0
(-1802 1150);
DISPLAY 0.638298 (-1802 1150);
PAINT MONO (-1802 1150);
FORCEPROP 2 LAST CDS_LIB standard
J 0
(-1550 1150);
PAINT MONO (-1550 1150);
DISPLAY INVISIBLE (-1550 1150);
FORCEPROP 1 LAST OFFPAGE TRUE
J 0
(-1225 1025);
DISPLAY 0.872340 (-1225 1025);
DISPLAY INVISIBLE (-1225 1025);
FORCEPROP 1 LAST COMMENT_BODY TRUE
J 0
(-1425 1050);
DISPLAY 0.872340 (-1425 1050);
PAINT GREEN (-1425 1050);
DISPLAY INVISIBLE (-1425 1050);
FORCEPROP 2 LAST PATH I183
J 2
(-2400 1200);
DISPLAY 1.021277 (-2400 1200);
DISPLAY INVISIBLE (-2400 1200);
FORCEADD OFFPAGE..1
(-2675 2800);
FORCEPROP 2 LAST $XR0 21 
J 0
(-2896 2800);
DISPLAY 0.638298 (-2896 2800);
PAINT MONO (-2896 2800);
FORCEPROP 2 LAST CDS_LIB standard
J 0
(-2675 2800);
PAINT MONO (-2675 2800);
DISPLAY INVISIBLE (-2675 2800);
FORCEPROP 1 LAST OFFPAGE TRUE
J 0
(-2350 2675);
DISPLAY 0.872340 (-2350 2675);
DISPLAY INVISIBLE (-2350 2675);
FORCEPROP 1 LAST COMMENT_BODY TRUE
J 0
(-2550 2700);
DISPLAY 0.872340 (-2550 2700);
PAINT GREEN (-2550 2700);
DISPLAY INVISIBLE (-2550 2700);
FORCEPROP 2 LAST PATH I19
J 0
(-2625 2875);
DISPLAY 1.021277 (-2625 2875);
DISPLAY INVISIBLE (-2625 2875);
FORCEADD OFFPAGE..2
R 2
(-2675 -50);
FORCEPROP 2 LAST $XR0 84 
J 0
(-2929 -50);
DISPLAY 0.638298 (-2929 -50);
PAINT MONO (-2929 -50);
FORCEPROP 2 LAST CDS_LIB standard
J 0
(-2675 -50);
PAINT MONO (-2675 -50);
DISPLAY INVISIBLE (-2675 -50);
FORCEPROP 1 LAST OFFPAGE TRUE
J 2
(-3000 -175);
DISPLAY 0.872340 (-3000 -175);
DISPLAY INVISIBLE (-3000 -175);
FORCEPROP 1 LAST COMMENT_BODY TRUE
J 2
(-2630 -145);
DISPLAY 0.872340 (-2630 -145);
PAINT GREEN (-2630 -145);
DISPLAY INVISIBLE (-2630 -145);
FORCEPROP 2 LAST PATH I2
J 0
(-2625 25);
DISPLAY 1.021277 (-2625 25);
DISPLAY INVISIBLE (-2625 25);
FORCEADD OFFPAGE..1
(-2675 2950);
FORCEPROP 2 LAST $XR0 21 
J 0
(-2896 2950);
DISPLAY 0.638298 (-2896 2950);
PAINT MONO (-2896 2950);
FORCEPROP 2 LAST CDS_LIB standard
J 0
(-2675 2950);
PAINT MONO (-2675 2950);
DISPLAY INVISIBLE (-2675 2950);
FORCEPROP 1 LAST OFFPAGE TRUE
J 0
(-2350 2825);
DISPLAY 0.872340 (-2350 2825);
DISPLAY INVISIBLE (-2350 2825);
FORCEPROP 1 LAST COMMENT_BODY TRUE
J 0
(-2550 2850);
DISPLAY 0.872340 (-2550 2850);
PAINT GREEN (-2550 2850);
DISPLAY INVISIBLE (-2550 2850);
FORCEPROP 2 LAST PATH I20
J 0
(-2625 3025);
DISPLAY 1.021277 (-2625 3025);
DISPLAY INVISIBLE (-2625 3025);
FORCEADD OFFPAGE..1
(-2675 3050);
FORCEPROP 2 LAST $XR1 85 
J 0
(-2986 3050);
DISPLAY 0.638298 (-2986 3050);
PAINT MONO (-2986 3050);
FORCEPROP 2 LAST $XR0 21 
J 0
(-2896 3050);
DISPLAY 0.638298 (-2896 3050);
PAINT MONO (-2896 3050);
FORCEPROP 2 LAST CDS_LIB standard
J 0
(-2675 3050);
PAINT MONO (-2675 3050);
DISPLAY INVISIBLE (-2675 3050);
FORCEPROP 1 LAST OFFPAGE TRUE
J 0
(-2350 2925);
DISPLAY 0.872340 (-2350 2925);
DISPLAY INVISIBLE (-2350 2925);
FORCEPROP 1 LAST COMMENT_BODY TRUE
J 0
(-2550 2950);
DISPLAY 0.872340 (-2550 2950);
PAINT GREEN (-2550 2950);
DISPLAY INVISIBLE (-2550 2950);
FORCEPROP 2 LAST PATH I21
J 0
(-2625 3125);
DISPLAY 1.021277 (-2625 3125);
DISPLAY INVISIBLE (-2625 3125);
FORCEADD OFFPAGE..1
(-2675 3100);
FORCEPROP 2 LAST $XR1 85 
J 0
(-2986 3100);
DISPLAY 0.638298 (-2986 3100);
PAINT MONO (-2986 3100);
FORCEPROP 2 LAST $XR0 21 
J 0
(-2896 3100);
DISPLAY 0.638298 (-2896 3100);
PAINT MONO (-2896 3100);
FORCEPROP 2 LAST CDS_LIB standard
J 0
(-2675 3100);
PAINT MONO (-2675 3100);
DISPLAY INVISIBLE (-2675 3100);
FORCEPROP 1 LAST OFFPAGE TRUE
J 0
(-2350 2975);
DISPLAY 0.872340 (-2350 2975);
DISPLAY INVISIBLE (-2350 2975);
FORCEPROP 1 LAST COMMENT_BODY TRUE
J 0
(-2550 3000);
DISPLAY 0.872340 (-2550 3000);
PAINT GREEN (-2550 3000);
DISPLAY INVISIBLE (-2550 3000);
FORCEPROP 2 LAST PATH I22
J 0
(-2625 3175);
DISPLAY 1.021277 (-2625 3175);
DISPLAY INVISIBLE (-2625 3175);
FORCEADD OFFPAGE..1
(-2675 3525);
FORCEPROP 2 LAST $XR1 85 
J 0
(-2986 3525);
DISPLAY 0.638298 (-2986 3525);
PAINT MONO (-2986 3525);
FORCEPROP 2 LAST $XR0 21 
J 0
(-2896 3525);
DISPLAY 0.638298 (-2896 3525);
PAINT MONO (-2896 3525);
FORCEPROP 2 LAST CDS_LIB standard
J 0
(-2675 3525);
PAINT MONO (-2675 3525);
DISPLAY INVISIBLE (-2675 3525);
FORCEPROP 1 LAST OFFPAGE TRUE
J 0
(-2350 3400);
DISPLAY 0.872340 (-2350 3400);
DISPLAY INVISIBLE (-2350 3400);
FORCEPROP 1 LAST COMMENT_BODY TRUE
J 0
(-2550 3425);
DISPLAY 0.872340 (-2550 3425);
PAINT GREEN (-2550 3425);
DISPLAY INVISIBLE (-2550 3425);
FORCEPROP 2 LAST PATH I23
J 0
(-2625 3600);
DISPLAY 1.021277 (-2625 3600);
DISPLAY INVISIBLE (-2625 3600);
FORCEADD TAP..1
R 2
(-1750 1750);
FORCEPROP 3 LASTPIN (-1700 1750) SIG_NAME M_B_CPU0_SB_CB<1>
J 0
(-1690 1760);
DISPLAY 0.659574 (-1690 1760);
PAINT MONO (-1690 1760);
DISPLAY INVISIBLE (-1690 1760);
FORCEPROP 1 LASTPIN (-1700 1750) BN 1
J 2
(-1688 1758);
DISPLAY 0.680851 (-1688 1758);
PAINT GREEN (-1688 1758);
FORCEPROP 2 LAST CDS_LIB standard
J 0
(-1750 1750);
DISPLAY INVISIBLE (-1750 1750);
FORCEPROP 1 LAST BODY_TYPE PLUMBING
J 2
(-1750 1800);
DISPLAY 0.872340 (-1750 1800);
PAINT GREEN (-1750 1800);
DISPLAY INVISIBLE (-1750 1800);
FORCEPROP 1 LAST HDL_TAP TRUE
J 2
(-2075 1625);
DISPLAY 0.872340 (-2075 1625);
DISPLAY INVISIBLE (-2075 1625);
FORCEPROP 1 LAST PATH I24
J 2
(-1748 1750);
DISPLAY 0.872340 (-1748 1750);
PAINT GREEN (-1748 1750);
DISPLAY INVISIBLE (-1748 1750);
FORCEADD TAP..1
R 2
(-1750 1700);
FORCEPROP 3 LASTPIN (-1700 1700) SIG_NAME M_B_CPU0_SB_CB<0>
J 0
(-1690 1710);
DISPLAY 0.659574 (-1690 1710);
PAINT MONO (-1690 1710);
DISPLAY INVISIBLE (-1690 1710);
FORCEPROP 1 LASTPIN (-1700 1700) BN 0
J 2
(-1688 1708);
DISPLAY 0.680851 (-1688 1708);
PAINT GREEN (-1688 1708);
FORCEPROP 2 LAST CDS_LIB standard
J 0
(-1750 1700);
PAINT MONO (-1750 1700);
DISPLAY INVISIBLE (-1750 1700);
FORCEPROP 1 LAST BODY_TYPE PLUMBING
J 2
(-1750 1750);
DISPLAY 0.872340 (-1750 1750);
PAINT GREEN (-1750 1750);
DISPLAY INVISIBLE (-1750 1750);
FORCEPROP 1 LAST HDL_TAP TRUE
J 2
(-2075 1575);
DISPLAY 0.872340 (-2075 1575);
DISPLAY INVISIBLE (-2075 1575);
FORCEPROP 1 LAST PATH I25
J 2
(-1748 1700);
DISPLAY 0.872340 (-1748 1700);
PAINT GREEN (-1748 1700);
DISPLAY INVISIBLE (-1748 1700);
FORCEADD TAP..1
R 2
(-1750 1800);
FORCEPROP 3 LASTPIN (-1700 1800) SIG_NAME M_B_CPU0_SB_CB<2>
J 0
(-1690 1810);
DISPLAY 0.659574 (-1690 1810);
PAINT MONO (-1690 1810);
DISPLAY INVISIBLE (-1690 1810);
FORCEPROP 1 LASTPIN (-1700 1800) BN 2
J 2
(-1688 1808);
DISPLAY 0.680851 (-1688 1808);
PAINT GREEN (-1688 1808);
FORCEPROP 2 LAST CDS_LIB standard
J 0
(-1750 1800);
DISPLAY INVISIBLE (-1750 1800);
FORCEPROP 1 LAST BODY_TYPE PLUMBING
J 2
(-1750 1850);
DISPLAY 0.872340 (-1750 1850);
PAINT GREEN (-1750 1850);
DISPLAY INVISIBLE (-1750 1850);
FORCEPROP 1 LAST HDL_TAP TRUE
J 2
(-2075 1675);
DISPLAY 0.872340 (-2075 1675);
DISPLAY INVISIBLE (-2075 1675);
FORCEPROP 1 LAST PATH I26
J 2
(-1748 1800);
DISPLAY 0.872340 (-1748 1800);
PAINT GREEN (-1748 1800);
DISPLAY INVISIBLE (-1748 1800);
FORCEADD TAP..1
R 2
(-1750 1850);
FORCEPROP 3 LASTPIN (-1700 1850) SIG_NAME M_B_CPU0_SB_CB<3>
J 0
(-1690 1860);
DISPLAY 0.659574 (-1690 1860);
PAINT MONO (-1690 1860);
DISPLAY INVISIBLE (-1690 1860);
FORCEPROP 1 LASTPIN (-1700 1850) BN 3
J 2
(-1688 1858);
DISPLAY 0.680851 (-1688 1858);
PAINT GREEN (-1688 1858);
FORCEPROP 2 LAST CDS_LIB standard
J 0
(-1750 1850);
DISPLAY INVISIBLE (-1750 1850);
FORCEPROP 1 LAST BODY_TYPE PLUMBING
J 2
(-1750 1900);
DISPLAY 0.872340 (-1750 1900);
PAINT GREEN (-1750 1900);
DISPLAY INVISIBLE (-1750 1900);
FORCEPROP 1 LAST HDL_TAP TRUE
J 2
(-2075 1725);
DISPLAY 0.872340 (-2075 1725);
DISPLAY INVISIBLE (-2075 1725);
FORCEPROP 1 LAST PATH I27
J 2
(-1748 1850);
DISPLAY 0.872340 (-1748 1850);
PAINT GREEN (-1748 1850);
DISPLAY INVISIBLE (-1748 1850);
FORCEADD TAP..1
R 2
(-1750 1900);
FORCEPROP 3 LASTPIN (-1700 1900) SIG_NAME M_B_CPU0_SB_CB<4>
J 0
(-1690 1910);
DISPLAY 0.659574 (-1690 1910);
PAINT MONO (-1690 1910);
DISPLAY INVISIBLE (-1690 1910);
FORCEPROP 1 LASTPIN (-1700 1900) BN 4
J 2
(-1688 1908);
DISPLAY 0.680851 (-1688 1908);
PAINT GREEN (-1688 1908);
FORCEPROP 2 LAST CDS_LIB standard
J 0
(-1750 1900);
DISPLAY INVISIBLE (-1750 1900);
FORCEPROP 1 LAST BODY_TYPE PLUMBING
J 2
(-1750 1950);
DISPLAY 0.872340 (-1750 1950);
PAINT GREEN (-1750 1950);
DISPLAY INVISIBLE (-1750 1950);
FORCEPROP 1 LAST HDL_TAP TRUE
J 2
(-2075 1775);
DISPLAY 0.872340 (-2075 1775);
DISPLAY INVISIBLE (-2075 1775);
FORCEPROP 1 LAST PATH I28
J 2
(-1748 1900);
DISPLAY 0.872340 (-1748 1900);
PAINT GREEN (-1748 1900);
DISPLAY INVISIBLE (-1748 1900);
FORCEADD TAP..1
R 2
(-1750 2000);
FORCEPROP 3 LASTPIN (-1700 2000) SIG_NAME M_B_CPU0_SB_CB<6>
J 0
(-1690 2010);
DISPLAY 0.659574 (-1690 2010);
PAINT MONO (-1690 2010);
DISPLAY INVISIBLE (-1690 2010);
FORCEPROP 1 LASTPIN (-1700 2000) BN 6
J 2
(-1688 2008);
DISPLAY 0.680851 (-1688 2008);
PAINT GREEN (-1688 2008);
FORCEPROP 2 LAST CDS_LIB standard
J 0
(-1750 2000);
DISPLAY INVISIBLE (-1750 2000);
FORCEPROP 1 LAST BODY_TYPE PLUMBING
J 2
(-1750 2050);
DISPLAY 0.872340 (-1750 2050);
PAINT GREEN (-1750 2050);
DISPLAY INVISIBLE (-1750 2050);
FORCEPROP 1 LAST HDL_TAP TRUE
J 2
(-2075 1875);
DISPLAY 0.872340 (-2075 1875);
DISPLAY INVISIBLE (-2075 1875);
FORCEPROP 1 LAST PATH I29
J 2
(-1748 2000);
DISPLAY 0.872340 (-1748 2000);
PAINT GREEN (-1748 2000);
DISPLAY INVISIBLE (-1748 2000);
FORCEADD OFFPAGE..2
R 2
(-2675 450);
FORCEPROP 2 LAST $XR0 21 
J 0
(-2929 450);
DISPLAY 0.638298 (-2929 450);
PAINT MONO (-2929 450);
FORCEPROP 2 LAST CDS_LIB standard
J 0
(-2675 450);
PAINT MONO (-2675 450);
DISPLAY INVISIBLE (-2675 450);
FORCEPROP 1 LAST OFFPAGE TRUE
J 2
(-3000 325);
DISPLAY 0.872340 (-3000 325);
DISPLAY INVISIBLE (-3000 325);
FORCEPROP 1 LAST COMMENT_BODY TRUE
J 2
(-2630 355);
DISPLAY 0.872340 (-2630 355);
PAINT GREEN (-2630 355);
DISPLAY INVISIBLE (-2630 355);
FORCEPROP 2 LAST PATH I3
J 0
(-2625 525);
DISPLAY 1.021277 (-2625 525);
DISPLAY INVISIBLE (-2625 525);
FORCEADD TAP..1
R 2
(-1750 1950);
FORCEPROP 3 LASTPIN (-1700 1950) SIG_NAME M_B_CPU0_SB_CB<5>
J 0
(-1690 1960);
DISPLAY 0.659574 (-1690 1960);
PAINT MONO (-1690 1960);
DISPLAY INVISIBLE (-1690 1960);
FORCEPROP 1 LASTPIN (-1700 1950) BN 5
J 2
(-1688 1958);
DISPLAY 0.680851 (-1688 1958);
PAINT GREEN (-1688 1958);
FORCEPROP 2 LAST CDS_LIB standard
J 0
(-1750 1950);
DISPLAY INVISIBLE (-1750 1950);
FORCEPROP 1 LAST BODY_TYPE PLUMBING
J 2
(-1750 2000);
DISPLAY 0.872340 (-1750 2000);
PAINT GREEN (-1750 2000);
DISPLAY INVISIBLE (-1750 2000);
FORCEPROP 1 LAST HDL_TAP TRUE
J 2
(-2075 1825);
DISPLAY 0.872340 (-2075 1825);
DISPLAY INVISIBLE (-2075 1825);
FORCEPROP 1 LAST PATH I30
J 2
(-1748 1950);
DISPLAY 0.872340 (-1748 1950);
PAINT GREEN (-1748 1950);
DISPLAY INVISIBLE (-1748 1950);
FORCEADD TAP..1
R 2
(-1750 2050);
FORCEPROP 3 LASTPIN (-1700 2050) SIG_NAME M_B_CPU0_SB_CB<7>
J 0
(-1690 2060);
DISPLAY 0.659574 (-1690 2060);
PAINT MONO (-1690 2060);
DISPLAY INVISIBLE (-1690 2060);
FORCEPROP 1 LASTPIN (-1700 2050) BN 7
J 2
(-1688 2058);
DISPLAY 0.680851 (-1688 2058);
PAINT GREEN (-1688 2058);
FORCEPROP 2 LAST CDS_LIB standard
J 0
(-1750 2050);
DISPLAY INVISIBLE (-1750 2050);
FORCEPROP 1 LAST BODY_TYPE PLUMBING
J 2
(-1750 2100);
DISPLAY 0.872340 (-1750 2100);
PAINT GREEN (-1750 2100);
DISPLAY INVISIBLE (-1750 2100);
FORCEPROP 1 LAST HDL_TAP TRUE
J 2
(-2075 1925);
DISPLAY 0.872340 (-2075 1925);
DISPLAY INVISIBLE (-2075 1925);
FORCEPROP 1 LAST PATH I31
J 2
(-1748 2050);
DISPLAY 0.872340 (-1748 2050);
PAINT GREEN (-1748 2050);
DISPLAY INVISIBLE (-1748 2050);
FORCEADD TAP..1
R 2
(-1750 2150);
FORCEPROP 3 LASTPIN (-1700 2150) SIG_NAME M_B_CPU0_SA_CB<0>
J 0
(-1690 2160);
DISPLAY 0.659574 (-1690 2160);
PAINT MONO (-1690 2160);
DISPLAY INVISIBLE (-1690 2160);
FORCEPROP 1 LASTPIN (-1700 2150) BN 0
J 2
(-1688 2158);
DISPLAY 0.680851 (-1688 2158);
PAINT GREEN (-1688 2158);
FORCEPROP 2 LAST CDS_LIB standard
J 0
(-1750 2150);
PAINT MONO (-1750 2150);
DISPLAY INVISIBLE (-1750 2150);
FORCEPROP 1 LAST BODY_TYPE PLUMBING
J 2
(-1750 2200);
DISPLAY 0.872340 (-1750 2200);
PAINT GREEN (-1750 2200);
DISPLAY INVISIBLE (-1750 2200);
FORCEPROP 1 LAST HDL_TAP TRUE
J 2
(-2075 2025);
DISPLAY 0.872340 (-2075 2025);
DISPLAY INVISIBLE (-2075 2025);
FORCEPROP 1 LAST PATH I32
J 2
(-1748 2150);
DISPLAY 0.872340 (-1748 2150);
PAINT GREEN (-1748 2150);
DISPLAY INVISIBLE (-1748 2150);
FORCEADD TAP..1
R 2
(-1750 2200);
FORCEPROP 3 LASTPIN (-1700 2200) SIG_NAME M_B_CPU0_SA_CB<1>
J 0
(-1690 2210);
DISPLAY 0.659574 (-1690 2210);
PAINT MONO (-1690 2210);
DISPLAY INVISIBLE (-1690 2210);
FORCEPROP 1 LASTPIN (-1700 2200) BN 1
J 2
(-1688 2208);
DISPLAY 0.680851 (-1688 2208);
PAINT GREEN (-1688 2208);
FORCEPROP 2 LAST CDS_LIB standard
J 0
(-1750 2200);
DISPLAY INVISIBLE (-1750 2200);
FORCEPROP 1 LAST BODY_TYPE PLUMBING
J 2
(-1750 2250);
DISPLAY 0.872340 (-1750 2250);
PAINT GREEN (-1750 2250);
DISPLAY INVISIBLE (-1750 2250);
FORCEPROP 1 LAST HDL_TAP TRUE
J 2
(-2075 2075);
DISPLAY 0.872340 (-2075 2075);
DISPLAY INVISIBLE (-2075 2075);
FORCEPROP 1 LAST PATH I33
J 2
(-1748 2200);
DISPLAY 0.872340 (-1748 2200);
PAINT GREEN (-1748 2200);
DISPLAY INVISIBLE (-1748 2200);
FORCEADD TAP..1
R 2
(-1750 2250);
FORCEPROP 3 LASTPIN (-1700 2250) SIG_NAME M_B_CPU0_SA_CB<2>
J 0
(-1690 2260);
DISPLAY 0.659574 (-1690 2260);
PAINT MONO (-1690 2260);
DISPLAY INVISIBLE (-1690 2260);
FORCEPROP 1 LASTPIN (-1700 2250) BN 2
J 2
(-1688 2258);
DISPLAY 0.680851 (-1688 2258);
PAINT GREEN (-1688 2258);
FORCEPROP 2 LAST CDS_LIB standard
J 0
(-1750 2250);
DISPLAY INVISIBLE (-1750 2250);
FORCEPROP 1 LAST BODY_TYPE PLUMBING
J 2
(-1750 2300);
DISPLAY 0.872340 (-1750 2300);
PAINT GREEN (-1750 2300);
DISPLAY INVISIBLE (-1750 2300);
FORCEPROP 1 LAST HDL_TAP TRUE
J 2
(-2075 2125);
DISPLAY 0.872340 (-2075 2125);
DISPLAY INVISIBLE (-2075 2125);
FORCEPROP 1 LAST PATH I34
J 2
(-1748 2250);
DISPLAY 0.872340 (-1748 2250);
PAINT GREEN (-1748 2250);
DISPLAY INVISIBLE (-1748 2250);
FORCEADD TAP..1
R 2
(-1750 2300);
FORCEPROP 3 LASTPIN (-1700 2300) SIG_NAME M_B_CPU0_SA_CB<3>
J 0
(-1690 2310);
DISPLAY 0.659574 (-1690 2310);
PAINT MONO (-1690 2310);
DISPLAY INVISIBLE (-1690 2310);
FORCEPROP 1 LASTPIN (-1700 2300) BN 3
J 2
(-1688 2308);
DISPLAY 0.680851 (-1688 2308);
PAINT GREEN (-1688 2308);
FORCEPROP 2 LAST CDS_LIB standard
J 0
(-1750 2300);
DISPLAY INVISIBLE (-1750 2300);
FORCEPROP 1 LAST BODY_TYPE PLUMBING
J 2
(-1750 2350);
DISPLAY 0.872340 (-1750 2350);
PAINT GREEN (-1750 2350);
DISPLAY INVISIBLE (-1750 2350);
FORCEPROP 1 LAST HDL_TAP TRUE
J 2
(-2075 2175);
DISPLAY 0.872340 (-2075 2175);
DISPLAY INVISIBLE (-2075 2175);
FORCEPROP 1 LAST PATH I35
J 2
(-1748 2300);
DISPLAY 0.872340 (-1748 2300);
PAINT GREEN (-1748 2300);
DISPLAY INVISIBLE (-1748 2300);
FORCEADD TAP..1
R 2
(-1750 2350);
FORCEPROP 3 LASTPIN (-1700 2350) SIG_NAME M_B_CPU0_SA_CB<4>
J 0
(-1690 2360);
DISPLAY 0.659574 (-1690 2360);
PAINT MONO (-1690 2360);
DISPLAY INVISIBLE (-1690 2360);
FORCEPROP 1 LASTPIN (-1700 2350) BN 4
J 2
(-1688 2358);
DISPLAY 0.680851 (-1688 2358);
PAINT GREEN (-1688 2358);
FORCEPROP 2 LAST CDS_LIB standard
J 0
(-1750 2350);
DISPLAY INVISIBLE (-1750 2350);
FORCEPROP 1 LAST BODY_TYPE PLUMBING
J 2
(-1750 2400);
DISPLAY 0.872340 (-1750 2400);
PAINT GREEN (-1750 2400);
DISPLAY INVISIBLE (-1750 2400);
FORCEPROP 1 LAST HDL_TAP TRUE
J 2
(-2075 2225);
DISPLAY 0.872340 (-2075 2225);
DISPLAY INVISIBLE (-2075 2225);
FORCEPROP 1 LAST PATH I36
J 2
(-1748 2350);
DISPLAY 0.872340 (-1748 2350);
PAINT GREEN (-1748 2350);
DISPLAY INVISIBLE (-1748 2350);
FORCEADD TAP..1
R 2
(-1750 2400);
FORCEPROP 3 LASTPIN (-1700 2400) SIG_NAME M_B_CPU0_SA_CB<5>
J 0
(-1690 2410);
DISPLAY 0.659574 (-1690 2410);
PAINT MONO (-1690 2410);
DISPLAY INVISIBLE (-1690 2410);
FORCEPROP 1 LASTPIN (-1700 2400) BN 5
J 2
(-1688 2408);
DISPLAY 0.680851 (-1688 2408);
PAINT GREEN (-1688 2408);
FORCEPROP 2 LAST CDS_LIB standard
J 0
(-1750 2400);
DISPLAY INVISIBLE (-1750 2400);
FORCEPROP 1 LAST BODY_TYPE PLUMBING
J 2
(-1750 2450);
DISPLAY 0.872340 (-1750 2450);
PAINT GREEN (-1750 2450);
DISPLAY INVISIBLE (-1750 2450);
FORCEPROP 1 LAST HDL_TAP TRUE
J 2
(-2075 2275);
DISPLAY 0.872340 (-2075 2275);
DISPLAY INVISIBLE (-2075 2275);
FORCEPROP 1 LAST PATH I37
J 2
(-1748 2400);
DISPLAY 0.872340 (-1748 2400);
PAINT GREEN (-1748 2400);
DISPLAY INVISIBLE (-1748 2400);
FORCEADD TAP..1
R 2
(-1750 2500);
FORCEPROP 3 LASTPIN (-1700 2500) SIG_NAME M_B_CPU0_SA_CB<7>
J 0
(-1690 2510);
DISPLAY 0.659574 (-1690 2510);
PAINT MONO (-1690 2510);
DISPLAY INVISIBLE (-1690 2510);
FORCEPROP 1 LASTPIN (-1700 2500) BN 7
J 2
(-1688 2508);
DISPLAY 0.680851 (-1688 2508);
PAINT GREEN (-1688 2508);
FORCEPROP 2 LAST CDS_LIB standard
J 0
(-1750 2500);
DISPLAY INVISIBLE (-1750 2500);
FORCEPROP 1 LAST BODY_TYPE PLUMBING
J 2
(-1750 2550);
DISPLAY 0.872340 (-1750 2550);
PAINT GREEN (-1750 2550);
DISPLAY INVISIBLE (-1750 2550);
FORCEPROP 1 LAST HDL_TAP TRUE
J 2
(-2075 2375);
DISPLAY 0.872340 (-2075 2375);
DISPLAY INVISIBLE (-2075 2375);
FORCEPROP 1 LAST PATH I38
J 2
(-1748 2500);
DISPLAY 0.872340 (-1748 2500);
PAINT GREEN (-1748 2500);
DISPLAY INVISIBLE (-1748 2500);
FORCEADD TAP..1
R 2
(-1750 2450);
FORCEPROP 3 LASTPIN (-1700 2450) SIG_NAME M_B_CPU0_SA_CB<6>
J 0
(-1690 2460);
DISPLAY 0.659574 (-1690 2460);
PAINT MONO (-1690 2460);
DISPLAY INVISIBLE (-1690 2460);
FORCEPROP 1 LASTPIN (-1700 2450) BN 6
J 2
(-1688 2458);
DISPLAY 0.680851 (-1688 2458);
PAINT GREEN (-1688 2458);
FORCEPROP 2 LAST CDS_LIB standard
J 0
(-1750 2450);
DISPLAY INVISIBLE (-1750 2450);
FORCEPROP 1 LAST BODY_TYPE PLUMBING
J 2
(-1750 2500);
DISPLAY 0.872340 (-1750 2500);
PAINT GREEN (-1750 2500);
DISPLAY INVISIBLE (-1750 2500);
FORCEPROP 1 LAST HDL_TAP TRUE
J 2
(-2075 2325);
DISPLAY 0.872340 (-2075 2325);
DISPLAY INVISIBLE (-2075 2325);
FORCEPROP 1 LAST PATH I39
J 2
(-1748 2450);
DISPLAY 0.872340 (-1748 2450);
PAINT GREEN (-1748 2450);
DISPLAY INVISIBLE (-1748 2450);
FORCEADD OFFPAGE..2
R 2
(-2675 500);
FORCEPROP 2 LAST $XR0 21 
J 0
(-2929 500);
DISPLAY 0.638298 (-2929 500);
PAINT MONO (-2929 500);
FORCEPROP 2 LAST CDS_LIB standard
J 0
(-2675 500);
PAINT MONO (-2675 500);
DISPLAY INVISIBLE (-2675 500);
FORCEPROP 1 LAST OFFPAGE TRUE
J 2
(-3000 375);
DISPLAY 0.872340 (-3000 375);
DISPLAY INVISIBLE (-3000 375);
FORCEPROP 1 LAST COMMENT_BODY TRUE
J 2
(-2630 405);
DISPLAY 0.872340 (-2630 405);
PAINT GREEN (-2630 405);
DISPLAY INVISIBLE (-2630 405);
FORCEPROP 2 LAST PATH I4
J 0
(-2625 575);
DISPLAY 1.021277 (-2625 575);
DISPLAY INVISIBLE (-2625 575);
FORCEADD TAP..1
R 2
(-1750 3300);
FORCEPROP 3 LASTPIN (-1700 3300) SIG_NAME M_B_CPU0_SB_CA<2>
J 0
(-1690 3310);
DISPLAY 0.659574 (-1690 3310);
PAINT MONO (-1690 3310);
DISPLAY INVISIBLE (-1690 3310);
FORCEPROP 1 LASTPIN (-1700 3300) BN 2
J 2
(-1688 3308);
DISPLAY 0.680851 (-1688 3308);
PAINT GREEN (-1688 3308);
FORCEPROP 2 LAST CDS_LIB standard
J 0
(-1750 3300);
DISPLAY INVISIBLE (-1750 3300);
FORCEPROP 1 LAST BODY_TYPE PLUMBING
J 2
(-1750 3350);
DISPLAY 0.872340 (-1750 3350);
PAINT GREEN (-1750 3350);
DISPLAY INVISIBLE (-1750 3350);
FORCEPROP 1 LAST HDL_TAP TRUE
J 2
(-2075 3175);
DISPLAY 0.872340 (-2075 3175);
DISPLAY INVISIBLE (-2075 3175);
FORCEPROP 1 LAST PATH I40
J 2
(-1748 3300);
DISPLAY 0.872340 (-1748 3300);
PAINT GREEN (-1748 3300);
DISPLAY INVISIBLE (-1748 3300);
FORCEADD TAP..1
R 2
(-1750 3250);
FORCEPROP 3 LASTPIN (-1700 3250) SIG_NAME M_B_CPU0_SB_CA<1>
J 0
(-1690 3260);
DISPLAY 0.659574 (-1690 3260);
PAINT MONO (-1690 3260);
DISPLAY INVISIBLE (-1690 3260);
FORCEPROP 1 LASTPIN (-1700 3250) BN 1
J 2
(-1688 3258);
DISPLAY 0.680851 (-1688 3258);
PAINT GREEN (-1688 3258);
FORCEPROP 2 LAST CDS_LIB standard
J 0
(-1750 3250);
DISPLAY INVISIBLE (-1750 3250);
FORCEPROP 1 LAST BODY_TYPE PLUMBING
J 2
(-1750 3300);
DISPLAY 0.872340 (-1750 3300);
PAINT GREEN (-1750 3300);
DISPLAY INVISIBLE (-1750 3300);
FORCEPROP 1 LAST HDL_TAP TRUE
J 2
(-2075 3125);
DISPLAY 0.872340 (-2075 3125);
DISPLAY INVISIBLE (-2075 3125);
FORCEPROP 1 LAST PATH I41
J 2
(-1748 3250);
DISPLAY 0.872340 (-1748 3250);
PAINT GREEN (-1748 3250);
DISPLAY INVISIBLE (-1748 3250);
FORCEADD TAP..1
R 2
(-1750 3200);
FORCEPROP 3 LASTPIN (-1700 3200) SIG_NAME M_B_CPU0_SB_CA<0>
J 0
(-1690 3210);
DISPLAY 0.659574 (-1690 3210);
PAINT MONO (-1690 3210);
DISPLAY INVISIBLE (-1690 3210);
FORCEPROP 1 LASTPIN (-1700 3200) BN 0
J 2
(-1688 3208);
DISPLAY 0.680851 (-1688 3208);
PAINT GREEN (-1688 3208);
FORCEPROP 2 LAST CDS_LIB standard
J 0
(-1750 3200);
DISPLAY INVISIBLE (-1750 3200);
FORCEPROP 1 LAST BODY_TYPE PLUMBING
J 2
(-1750 3250);
DISPLAY 0.872340 (-1750 3250);
PAINT GREEN (-1750 3250);
DISPLAY INVISIBLE (-1750 3250);
FORCEPROP 1 LAST HDL_TAP TRUE
J 2
(-2075 3075);
DISPLAY 0.872340 (-2075 3075);
DISPLAY INVISIBLE (-2075 3075);
FORCEPROP 1 LAST PATH I42
J 2
(-1748 3200);
DISPLAY 0.872340 (-1748 3200);
PAINT GREEN (-1748 3200);
DISPLAY INVISIBLE (-1748 3200);
FORCEADD TAP..1
R 2
(-1750 3400);
FORCEPROP 3 LASTPIN (-1700 3400) SIG_NAME M_B_CPU0_SB_CA<4>
J 0
(-1690 3410);
DISPLAY 0.659574 (-1690 3410);
PAINT MONO (-1690 3410);
DISPLAY INVISIBLE (-1690 3410);
FORCEPROP 1 LASTPIN (-1700 3400) BN 4
J 2
(-1688 3408);
DISPLAY 0.680851 (-1688 3408);
PAINT GREEN (-1688 3408);
FORCEPROP 2 LAST CDS_LIB standard
J 0
(-1750 3400);
DISPLAY INVISIBLE (-1750 3400);
FORCEPROP 1 LAST BODY_TYPE PLUMBING
J 2
(-1750 3450);
DISPLAY 0.872340 (-1750 3450);
PAINT GREEN (-1750 3450);
DISPLAY INVISIBLE (-1750 3450);
FORCEPROP 1 LAST HDL_TAP TRUE
J 2
(-2075 3275);
DISPLAY 0.872340 (-2075 3275);
DISPLAY INVISIBLE (-2075 3275);
FORCEPROP 1 LAST PATH I43
J 2
(-1748 3400);
DISPLAY 0.872340 (-1748 3400);
PAINT GREEN (-1748 3400);
DISPLAY INVISIBLE (-1748 3400);
FORCEADD TAP..1
R 2
(-1750 3350);
FORCEPROP 3 LASTPIN (-1700 3350) SIG_NAME M_B_CPU0_SB_CA<3>
J 0
(-1690 3360);
DISPLAY 0.659574 (-1690 3360);
PAINT MONO (-1690 3360);
DISPLAY INVISIBLE (-1690 3360);
FORCEPROP 1 LASTPIN (-1700 3350) BN 3
J 2
(-1688 3358);
DISPLAY 0.680851 (-1688 3358);
PAINT GREEN (-1688 3358);
FORCEPROP 2 LAST CDS_LIB standard
J 0
(-1750 3350);
DISPLAY INVISIBLE (-1750 3350);
FORCEPROP 1 LAST BODY_TYPE PLUMBING
J 2
(-1750 3400);
DISPLAY 0.872340 (-1750 3400);
PAINT GREEN (-1750 3400);
DISPLAY INVISIBLE (-1750 3400);
FORCEPROP 1 LAST HDL_TAP TRUE
J 2
(-2075 3225);
DISPLAY 0.872340 (-2075 3225);
DISPLAY INVISIBLE (-2075 3225);
FORCEPROP 1 LAST PATH I44
J 2
(-1748 3350);
DISPLAY 0.872340 (-1748 3350);
PAINT GREEN (-1748 3350);
DISPLAY INVISIBLE (-1748 3350);
FORCEADD TAP..1
R 2
(-1750 3500);
FORCEPROP 3 LASTPIN (-1700 3500) SIG_NAME M_B_CPU0_SB_CA<6>
J 0
(-1690 3510);
DISPLAY 0.659574 (-1690 3510);
PAINT MONO (-1690 3510);
DISPLAY INVISIBLE (-1690 3510);
FORCEPROP 1 LASTPIN (-1700 3500) BN 6
J 2
(-1688 3508);
DISPLAY 0.680851 (-1688 3508);
PAINT GREEN (-1688 3508);
FORCEPROP 2 LAST CDS_LIB standard
J 0
(-1750 3500);
DISPLAY INVISIBLE (-1750 3500);
FORCEPROP 1 LAST BODY_TYPE PLUMBING
J 2
(-1750 3550);
DISPLAY 0.872340 (-1750 3550);
PAINT GREEN (-1750 3550);
DISPLAY INVISIBLE (-1750 3550);
FORCEPROP 1 LAST HDL_TAP TRUE
J 2
(-2075 3375);
DISPLAY 0.872340 (-2075 3375);
DISPLAY INVISIBLE (-2075 3375);
FORCEPROP 1 LAST PATH I45
J 2
(-1748 3500);
DISPLAY 0.872340 (-1748 3500);
PAINT GREEN (-1748 3500);
DISPLAY INVISIBLE (-1748 3500);
FORCEADD TAP..1
R 2
(-1750 3450);
FORCEPROP 3 LASTPIN (-1700 3450) SIG_NAME M_B_CPU0_SB_CA<5>
J 0
(-1690 3460);
DISPLAY 0.659574 (-1690 3460);
PAINT MONO (-1690 3460);
DISPLAY INVISIBLE (-1690 3460);
FORCEPROP 1 LASTPIN (-1700 3450) BN 5
J 2
(-1688 3458);
DISPLAY 0.680851 (-1688 3458);
PAINT GREEN (-1688 3458);
FORCEPROP 2 LAST CDS_LIB standard
J 0
(-1750 3450);
DISPLAY INVISIBLE (-1750 3450);
FORCEPROP 1 LAST BODY_TYPE PLUMBING
J 2
(-1750 3500);
DISPLAY 0.872340 (-1750 3500);
PAINT GREEN (-1750 3500);
DISPLAY INVISIBLE (-1750 3500);
FORCEPROP 1 LAST HDL_TAP TRUE
J 2
(-2075 3325);
DISPLAY 0.872340 (-2075 3325);
DISPLAY INVISIBLE (-2075 3325);
FORCEPROP 1 LAST PATH I46
J 2
(-1748 3450);
DISPLAY 0.872340 (-1748 3450);
PAINT GREEN (-1748 3450);
DISPLAY INVISIBLE (-1748 3450);
FORCEADD TAP..1
R 2
(-1750 3650);
FORCEPROP 3 LASTPIN (-1700 3650) SIG_NAME M_B_CPU0_SA_CA<1>
J 0
(-1690 3660);
DISPLAY 0.659574 (-1690 3660);
PAINT MONO (-1690 3660);
DISPLAY INVISIBLE (-1690 3660);
FORCEPROP 1 LASTPIN (-1700 3650) BN 1
J 2
(-1688 3658);
DISPLAY 0.680851 (-1688 3658);
PAINT GREEN (-1688 3658);
FORCEPROP 2 LAST CDS_LIB standard
J 0
(-1750 3650);
DISPLAY INVISIBLE (-1750 3650);
FORCEPROP 1 LAST BODY_TYPE PLUMBING
J 2
(-1750 3700);
DISPLAY 0.872340 (-1750 3700);
PAINT GREEN (-1750 3700);
DISPLAY INVISIBLE (-1750 3700);
FORCEPROP 1 LAST HDL_TAP TRUE
J 2
(-2075 3525);
DISPLAY 0.872340 (-2075 3525);
DISPLAY INVISIBLE (-2075 3525);
FORCEPROP 1 LAST PATH I47
J 2
(-1748 3650);
DISPLAY 0.872340 (-1748 3650);
PAINT GREEN (-1748 3650);
DISPLAY INVISIBLE (-1748 3650);
FORCEADD TAP..1
R 2
(-1750 3600);
FORCEPROP 3 LASTPIN (-1700 3600) SIG_NAME M_B_CPU0_SA_CA<0>
J 0
(-1690 3610);
DISPLAY 0.659574 (-1690 3610);
PAINT MONO (-1690 3610);
DISPLAY INVISIBLE (-1690 3610);
FORCEPROP 1 LASTPIN (-1700 3600) BN 0
J 2
(-1688 3608);
DISPLAY 0.680851 (-1688 3608);
PAINT GREEN (-1688 3608);
FORCEPROP 2 LAST CDS_LIB standard
J 0
(-1750 3600);
DISPLAY INVISIBLE (-1750 3600);
FORCEPROP 1 LAST BODY_TYPE PLUMBING
J 2
(-1750 3650);
DISPLAY 0.872340 (-1750 3650);
PAINT GREEN (-1750 3650);
DISPLAY INVISIBLE (-1750 3650);
FORCEPROP 1 LAST HDL_TAP TRUE
J 2
(-2075 3475);
DISPLAY 0.872340 (-2075 3475);
DISPLAY INVISIBLE (-2075 3475);
FORCEPROP 1 LAST PATH I48
J 2
(-1748 3600);
DISPLAY 0.872340 (-1748 3600);
PAINT GREEN (-1748 3600);
DISPLAY INVISIBLE (-1748 3600);
FORCEADD TAP..1
(-100 700);
FORCEPROP 3 LASTPIN (-150 700) SIG_NAME M_B_CPU0_SB_DQ<0>
J 0
(-140 710);
DISPLAY 0.659574 (-140 710);
PAINT MONO (-140 710);
DISPLAY INVISIBLE (-140 710);
FORCEPROP 1 LASTPIN (-150 700) BN 0
J 0
(-162 708);
DISPLAY 0.680851 (-162 708);
PAINT GREEN (-162 708);
FORCEPROP 2 LAST CDS_LIB standard
J 0
(-100 700);
PAINT MONO (-100 700);
DISPLAY INVISIBLE (-100 700);
FORCEPROP 1 LAST BODY_TYPE PLUMBING
J 0
(-100 750);
DISPLAY 0.872340 (-100 750);
PAINT GREEN (-100 750);
DISPLAY INVISIBLE (-100 750);
FORCEPROP 1 LAST HDL_TAP TRUE
J 0
(225 575);
DISPLAY 0.872340 (225 575);
DISPLAY INVISIBLE (225 575);
FORCEPROP 1 LAST PATH I49
J 0
(-102 700);
DISPLAY 0.872340 (-102 700);
PAINT GREEN (-102 700);
DISPLAY INVISIBLE (-102 700);
FORCEADD TAP..1
(-100 750);
FORCEPROP 3 LASTPIN (-150 750) SIG_NAME M_B_CPU0_SB_DQ<1>
J 0
(-140 760);
DISPLAY 0.659574 (-140 760);
PAINT MONO (-140 760);
DISPLAY INVISIBLE (-140 760);
FORCEPROP 1 LASTPIN (-150 750) BN 1
J 0
(-162 758);
DISPLAY 0.680851 (-162 758);
PAINT GREEN (-162 758);
FORCEPROP 2 LAST CDS_LIB standard
J 0
(-100 750);
PAINT MONO (-100 750);
DISPLAY INVISIBLE (-100 750);
FORCEPROP 1 LAST BODY_TYPE PLUMBING
J 0
(-100 800);
DISPLAY 0.872340 (-100 800);
PAINT GREEN (-100 800);
DISPLAY INVISIBLE (-100 800);
FORCEPROP 1 LAST HDL_TAP TRUE
J 0
(225 625);
DISPLAY 0.872340 (225 625);
DISPLAY INVISIBLE (225 625);
FORCEPROP 1 LAST PATH I50
J 0
(-102 750);
DISPLAY 0.872340 (-102 750);
PAINT GREEN (-102 750);
DISPLAY INVISIBLE (-102 750);
FORCEADD TAP..1
(-100 850);
FORCEPROP 3 LASTPIN (-150 850) SIG_NAME M_B_CPU0_SB_DQ<3>
J 0
(-140 860);
DISPLAY 0.659574 (-140 860);
PAINT MONO (-140 860);
DISPLAY INVISIBLE (-140 860);
FORCEPROP 1 LASTPIN (-150 850) BN 3
J 0
(-162 858);
DISPLAY 0.680851 (-162 858);
PAINT GREEN (-162 858);
FORCEPROP 2 LAST CDS_LIB standard
J 0
(-100 850);
PAINT MONO (-100 850);
DISPLAY INVISIBLE (-100 850);
FORCEPROP 1 LAST BODY_TYPE PLUMBING
J 0
(-100 900);
DISPLAY 0.872340 (-100 900);
PAINT GREEN (-100 900);
DISPLAY INVISIBLE (-100 900);
FORCEPROP 1 LAST HDL_TAP TRUE
J 0
(225 725);
DISPLAY 0.872340 (225 725);
DISPLAY INVISIBLE (225 725);
FORCEPROP 1 LAST PATH I51
J 0
(-102 850);
DISPLAY 0.872340 (-102 850);
PAINT GREEN (-102 850);
DISPLAY INVISIBLE (-102 850);
FORCEADD TAP..1
(-100 800);
FORCEPROP 3 LASTPIN (-150 800) SIG_NAME M_B_CPU0_SB_DQ<2>
J 0
(-140 810);
DISPLAY 0.659574 (-140 810);
PAINT MONO (-140 810);
DISPLAY INVISIBLE (-140 810);
FORCEPROP 1 LASTPIN (-150 800) BN 2
J 0
(-162 808);
DISPLAY 0.680851 (-162 808);
PAINT GREEN (-162 808);
FORCEPROP 2 LAST CDS_LIB standard
J 0
(-100 800);
PAINT MONO (-100 800);
DISPLAY INVISIBLE (-100 800);
FORCEPROP 1 LAST BODY_TYPE PLUMBING
J 0
(-100 850);
DISPLAY 0.872340 (-100 850);
PAINT GREEN (-100 850);
DISPLAY INVISIBLE (-100 850);
FORCEPROP 1 LAST HDL_TAP TRUE
J 0
(225 675);
DISPLAY 0.872340 (225 675);
DISPLAY INVISIBLE (225 675);
FORCEPROP 1 LAST PATH I52
J 0
(-102 800);
DISPLAY 0.872340 (-102 800);
PAINT GREEN (-102 800);
DISPLAY INVISIBLE (-102 800);
FORCEADD TAP..1
(-100 1000);
FORCEPROP 3 LASTPIN (-150 1000) SIG_NAME M_B_CPU0_SB_DQ<6>
J 0
(-140 1010);
DISPLAY 0.659574 (-140 1010);
PAINT MONO (-140 1010);
DISPLAY INVISIBLE (-140 1010);
FORCEPROP 1 LASTPIN (-150 1000) BN 6
J 0
(-162 1008);
DISPLAY 0.680851 (-162 1008);
PAINT GREEN (-162 1008);
FORCEPROP 2 LAST CDS_LIB standard
J 0
(-100 1000);
PAINT MONO (-100 1000);
DISPLAY INVISIBLE (-100 1000);
FORCEPROP 1 LAST BODY_TYPE PLUMBING
J 0
(-100 1050);
DISPLAY 0.872340 (-100 1050);
PAINT GREEN (-100 1050);
DISPLAY INVISIBLE (-100 1050);
FORCEPROP 1 LAST HDL_TAP TRUE
J 0
(225 875);
DISPLAY 0.872340 (225 875);
DISPLAY INVISIBLE (225 875);
FORCEPROP 1 LAST PATH I53
J 0
(-102 1000);
DISPLAY 0.872340 (-102 1000);
PAINT GREEN (-102 1000);
DISPLAY INVISIBLE (-102 1000);
FORCEADD TAP..1
(-100 950);
FORCEPROP 3 LASTPIN (-150 950) SIG_NAME M_B_CPU0_SB_DQ<5>
J 0
(-140 960);
DISPLAY 0.659574 (-140 960);
PAINT MONO (-140 960);
DISPLAY INVISIBLE (-140 960);
FORCEPROP 1 LASTPIN (-150 950) BN 5
J 0
(-162 958);
DISPLAY 0.680851 (-162 958);
PAINT GREEN (-162 958);
FORCEPROP 2 LAST CDS_LIB standard
J 0
(-100 950);
PAINT MONO (-100 950);
DISPLAY INVISIBLE (-100 950);
FORCEPROP 1 LAST BODY_TYPE PLUMBING
J 0
(-100 1000);
DISPLAY 0.872340 (-100 1000);
PAINT GREEN (-100 1000);
DISPLAY INVISIBLE (-100 1000);
FORCEPROP 1 LAST HDL_TAP TRUE
J 0
(225 825);
DISPLAY 0.872340 (225 825);
DISPLAY INVISIBLE (225 825);
FORCEPROP 1 LAST PATH I54
J 0
(-102 950);
DISPLAY 0.872340 (-102 950);
PAINT GREEN (-102 950);
DISPLAY INVISIBLE (-102 950);
FORCEADD TAP..1
(-100 900);
FORCEPROP 3 LASTPIN (-150 900) SIG_NAME M_B_CPU0_SB_DQ<4>
J 0
(-140 910);
DISPLAY 0.659574 (-140 910);
PAINT MONO (-140 910);
DISPLAY INVISIBLE (-140 910);
FORCEPROP 1 LASTPIN (-150 900) BN 4
J 0
(-162 908);
DISPLAY 0.680851 (-162 908);
PAINT GREEN (-162 908);
FORCEPROP 2 LAST CDS_LIB standard
J 0
(-100 900);
PAINT MONO (-100 900);
DISPLAY INVISIBLE (-100 900);
FORCEPROP 1 LAST BODY_TYPE PLUMBING
J 0
(-100 950);
DISPLAY 0.872340 (-100 950);
PAINT GREEN (-100 950);
DISPLAY INVISIBLE (-100 950);
FORCEPROP 1 LAST HDL_TAP TRUE
J 0
(225 775);
DISPLAY 0.872340 (225 775);
DISPLAY INVISIBLE (225 775);
FORCEPROP 1 LAST PATH I55
J 0
(-102 900);
DISPLAY 0.872340 (-102 900);
PAINT GREEN (-102 900);
DISPLAY INVISIBLE (-102 900);
FORCEADD TAP..1
(-100 1050);
FORCEPROP 3 LASTPIN (-150 1050) SIG_NAME M_B_CPU0_SB_DQ<7>
J 0
(-140 1060);
DISPLAY 0.659574 (-140 1060);
PAINT MONO (-140 1060);
DISPLAY INVISIBLE (-140 1060);
FORCEPROP 1 LASTPIN (-150 1050) BN 7
J 0
(-162 1058);
DISPLAY 0.680851 (-162 1058);
PAINT GREEN (-162 1058);
FORCEPROP 2 LAST CDS_LIB standard
J 0
(-100 1050);
PAINT MONO (-100 1050);
DISPLAY INVISIBLE (-100 1050);
FORCEPROP 1 LAST BODY_TYPE PLUMBING
J 0
(-100 1100);
DISPLAY 0.872340 (-100 1100);
PAINT GREEN (-100 1100);
DISPLAY INVISIBLE (-100 1100);
FORCEPROP 1 LAST HDL_TAP TRUE
J 0
(225 925);
DISPLAY 0.872340 (225 925);
DISPLAY INVISIBLE (225 925);
FORCEPROP 1 LAST PATH I56
J 0
(-102 1050);
DISPLAY 0.872340 (-102 1050);
PAINT GREEN (-102 1050);
DISPLAY INVISIBLE (-102 1050);
FORCEADD TAP..1
(-100 1100);
FORCEPROP 3 LASTPIN (-150 1100) SIG_NAME M_B_CPU0_SB_DQ<8>
J 0
(-140 1110);
DISPLAY 0.659574 (-140 1110);
PAINT MONO (-140 1110);
DISPLAY INVISIBLE (-140 1110);
FORCEPROP 1 LASTPIN (-150 1100) BN 8
J 0
(-162 1108);
DISPLAY 0.680851 (-162 1108);
PAINT GREEN (-162 1108);
FORCEPROP 2 LAST CDS_LIB standard
J 0
(-100 1100);
PAINT MONO (-100 1100);
DISPLAY INVISIBLE (-100 1100);
FORCEPROP 1 LAST BODY_TYPE PLUMBING
J 0
(-100 1150);
DISPLAY 0.872340 (-100 1150);
PAINT GREEN (-100 1150);
DISPLAY INVISIBLE (-100 1150);
FORCEPROP 1 LAST HDL_TAP TRUE
J 0
(225 975);
DISPLAY 0.872340 (225 975);
DISPLAY INVISIBLE (225 975);
FORCEPROP 1 LAST PATH I57
J 0
(-102 1100);
DISPLAY 0.872340 (-102 1100);
PAINT GREEN (-102 1100);
DISPLAY INVISIBLE (-102 1100);
FORCEADD TAP..1
(-100 1150);
FORCEPROP 3 LASTPIN (-150 1150) SIG_NAME M_B_CPU0_SB_DQ<9>
J 0
(-140 1160);
DISPLAY 0.659574 (-140 1160);
PAINT MONO (-140 1160);
DISPLAY INVISIBLE (-140 1160);
FORCEPROP 1 LASTPIN (-150 1150) BN 9
J 0
(-162 1158);
DISPLAY 0.680851 (-162 1158);
PAINT GREEN (-162 1158);
FORCEPROP 2 LAST CDS_LIB standard
J 0
(-100 1150);
PAINT MONO (-100 1150);
DISPLAY INVISIBLE (-100 1150);
FORCEPROP 1 LAST BODY_TYPE PLUMBING
J 0
(-100 1200);
DISPLAY 0.872340 (-100 1200);
PAINT GREEN (-100 1200);
DISPLAY INVISIBLE (-100 1200);
FORCEPROP 1 LAST HDL_TAP TRUE
J 0
(225 1025);
DISPLAY 0.872340 (225 1025);
DISPLAY INVISIBLE (225 1025);
FORCEPROP 1 LAST PATH I58
J 0
(-102 1150);
DISPLAY 0.872340 (-102 1150);
PAINT GREEN (-102 1150);
DISPLAY INVISIBLE (-102 1150);
FORCEADD TAP..1
(-100 1200);
FORCEPROP 3 LASTPIN (-150 1200) SIG_NAME M_B_CPU0_SB_DQ<10>
J 0
(-140 1210);
DISPLAY 0.659574 (-140 1210);
PAINT MONO (-140 1210);
DISPLAY INVISIBLE (-140 1210);
FORCEPROP 1 LASTPIN (-150 1200) BN 10
J 0
(-162 1208);
DISPLAY 0.680851 (-162 1208);
PAINT GREEN (-162 1208);
FORCEPROP 2 LAST CDS_LIB standard
J 0
(-100 1200);
PAINT MONO (-100 1200);
DISPLAY INVISIBLE (-100 1200);
FORCEPROP 1 LAST BODY_TYPE PLUMBING
J 0
(-100 1250);
DISPLAY 0.872340 (-100 1250);
PAINT GREEN (-100 1250);
DISPLAY INVISIBLE (-100 1250);
FORCEPROP 1 LAST HDL_TAP TRUE
J 0
(225 1075);
DISPLAY 0.872340 (225 1075);
DISPLAY INVISIBLE (225 1075);
FORCEPROP 1 LAST PATH I59
J 0
(-102 1200);
DISPLAY 0.872340 (-102 1200);
PAINT GREEN (-102 1200);
DISPLAY INVISIBLE (-102 1200);
FORCEADD OFFPAGE..1
(-2600 1350);
FORCEPROP 2 LAST $XR7 89 
J 0
(-3122 1314);
DISPLAY 0.638298 (-3122 1314);
PAINT MONO (-3122 1314);
FORCEPROP 2 LAST $XR6 88 
J 0
(-3032 1314);
DISPLAY 0.638298 (-3032 1314);
PAINT MONO (-3032 1314);
FORCEPROP 2 LAST $XR5 87 
J 0
(-2942 1314);
DISPLAY 0.638298 (-2942 1314);
PAINT MONO (-2942 1314);
FORCEPROP 2 LAST $XR4 86 
J 0
(-2852 1314);
DISPLAY 0.638298 (-2852 1314);
PAINT MONO (-2852 1314);
FORCEPROP 2 LAST $XR3 85 
J 0
(-3122 1350);
DISPLAY 0.638298 (-3122 1350);
PAINT MONO (-3122 1350);
FORCEPROP 2 LAST $XR2 83 
J 0
(-3032 1350);
DISPLAY 0.638298 (-3032 1350);
PAINT MONO (-3032 1350);
FORCEPROP 2 LAST $XR1 82 
J 0
(-2942 1350);
DISPLAY 0.638298 (-2942 1350);
PAINT MONO (-2942 1350);
FORCEPROP 2 LAST $XR0 229 
J 0
(-2852 1350);
DISPLAY 0.638298 (-2852 1350);
PAINT MONO (-2852 1350);
FORCEPROP 2 LAST CDS_LIB standard
J 0
(-2600 1350);
PAINT MONO (-2600 1350);
DISPLAY INVISIBLE (-2600 1350);
FORCEPROP 1 LAST OFFPAGE TRUE
J 0
(-2275 1225);
DISPLAY 0.872340 (-2275 1225);
DISPLAY INVISIBLE (-2275 1225);
FORCEPROP 1 LAST COMMENT_BODY TRUE
J 0
(-2475 1250);
DISPLAY 0.872340 (-2475 1250);
PAINT GREEN (-2475 1250);
DISPLAY INVISIBLE (-2475 1250);
FORCEPROP 2 LAST PATH I6
J 0
(-2550 1425);
DISPLAY 1.021277 (-2550 1425);
DISPLAY INVISIBLE (-2550 1425);
FORCEADD TAP..1
(-100 1250);
FORCEPROP 3 LASTPIN (-150 1250) SIG_NAME M_B_CPU0_SB_DQ<11>
J 0
(-140 1260);
DISPLAY 0.659574 (-140 1260);
PAINT MONO (-140 1260);
DISPLAY INVISIBLE (-140 1260);
FORCEPROP 1 LASTPIN (-150 1250) BN 11
J 0
(-162 1258);
DISPLAY 0.680851 (-162 1258);
PAINT GREEN (-162 1258);
FORCEPROP 2 LAST CDS_LIB standard
J 0
(-100 1250);
PAINT MONO (-100 1250);
DISPLAY INVISIBLE (-100 1250);
FORCEPROP 1 LAST BODY_TYPE PLUMBING
J 0
(-100 1300);
DISPLAY 0.872340 (-100 1300);
PAINT GREEN (-100 1300);
DISPLAY INVISIBLE (-100 1300);
FORCEPROP 1 LAST HDL_TAP TRUE
J 0
(225 1125);
DISPLAY 0.872340 (225 1125);
DISPLAY INVISIBLE (225 1125);
FORCEPROP 1 LAST PATH I60
J 0
(-102 1250);
DISPLAY 0.872340 (-102 1250);
PAINT GREEN (-102 1250);
DISPLAY INVISIBLE (-102 1250);
FORCEADD TAP..1
(-100 1300);
FORCEPROP 3 LASTPIN (-150 1300) SIG_NAME M_B_CPU0_SB_DQ<12>
J 0
(-140 1310);
DISPLAY 0.659574 (-140 1310);
PAINT MONO (-140 1310);
DISPLAY INVISIBLE (-140 1310);
FORCEPROP 1 LASTPIN (-150 1300) BN 12
J 0
(-162 1308);
DISPLAY 0.680851 (-162 1308);
PAINT GREEN (-162 1308);
FORCEPROP 2 LAST CDS_LIB standard
J 0
(-100 1300);
PAINT MONO (-100 1300);
DISPLAY INVISIBLE (-100 1300);
FORCEPROP 1 LAST BODY_TYPE PLUMBING
J 0
(-100 1350);
DISPLAY 0.872340 (-100 1350);
PAINT GREEN (-100 1350);
DISPLAY INVISIBLE (-100 1350);
FORCEPROP 1 LAST HDL_TAP TRUE
J 0
(225 1175);
DISPLAY 0.872340 (225 1175);
DISPLAY INVISIBLE (225 1175);
FORCEPROP 1 LAST PATH I61
J 0
(-102 1300);
DISPLAY 0.872340 (-102 1300);
PAINT GREEN (-102 1300);
DISPLAY INVISIBLE (-102 1300);
FORCEADD TAP..1
(-100 1350);
FORCEPROP 3 LASTPIN (-150 1350) SIG_NAME M_B_CPU0_SB_DQ<13>
J 0
(-140 1360);
DISPLAY 0.659574 (-140 1360);
PAINT MONO (-140 1360);
DISPLAY INVISIBLE (-140 1360);
FORCEPROP 1 LASTPIN (-150 1350) BN 13
J 0
(-162 1358);
DISPLAY 0.680851 (-162 1358);
PAINT GREEN (-162 1358);
FORCEPROP 2 LAST CDS_LIB standard
J 0
(-100 1350);
PAINT MONO (-100 1350);
DISPLAY INVISIBLE (-100 1350);
FORCEPROP 1 LAST BODY_TYPE PLUMBING
J 0
(-100 1400);
DISPLAY 0.872340 (-100 1400);
PAINT GREEN (-100 1400);
DISPLAY INVISIBLE (-100 1400);
FORCEPROP 1 LAST HDL_TAP TRUE
J 0
(225 1225);
DISPLAY 0.872340 (225 1225);
DISPLAY INVISIBLE (225 1225);
FORCEPROP 1 LAST PATH I62
J 0
(-102 1350);
DISPLAY 0.872340 (-102 1350);
PAINT GREEN (-102 1350);
DISPLAY INVISIBLE (-102 1350);
FORCEADD TAP..1
(-100 1400);
FORCEPROP 3 LASTPIN (-150 1400) SIG_NAME M_B_CPU0_SB_DQ<14>
J 0
(-140 1410);
DISPLAY 0.659574 (-140 1410);
PAINT MONO (-140 1410);
DISPLAY INVISIBLE (-140 1410);
FORCEPROP 1 LASTPIN (-150 1400) BN 14
J 0
(-162 1408);
DISPLAY 0.680851 (-162 1408);
PAINT GREEN (-162 1408);
FORCEPROP 2 LAST CDS_LIB standard
J 0
(-100 1400);
PAINT MONO (-100 1400);
DISPLAY INVISIBLE (-100 1400);
FORCEPROP 1 LAST BODY_TYPE PLUMBING
J 0
(-100 1450);
DISPLAY 0.872340 (-100 1450);
PAINT GREEN (-100 1450);
DISPLAY INVISIBLE (-100 1450);
FORCEPROP 1 LAST HDL_TAP TRUE
J 0
(225 1275);
DISPLAY 0.872340 (225 1275);
DISPLAY INVISIBLE (225 1275);
FORCEPROP 1 LAST PATH I63
J 0
(-102 1400);
DISPLAY 0.872340 (-102 1400);
PAINT GREEN (-102 1400);
DISPLAY INVISIBLE (-102 1400);
FORCEADD TAP..1
(-100 1450);
FORCEPROP 3 LASTPIN (-150 1450) SIG_NAME M_B_CPU0_SB_DQ<15>
J 0
(-140 1460);
DISPLAY 0.659574 (-140 1460);
PAINT MONO (-140 1460);
DISPLAY INVISIBLE (-140 1460);
FORCEPROP 1 LASTPIN (-150 1450) BN 15
J 0
(-162 1458);
DISPLAY 0.680851 (-162 1458);
PAINT GREEN (-162 1458);
FORCEPROP 2 LAST CDS_LIB standard
J 0
(-100 1450);
PAINT MONO (-100 1450);
DISPLAY INVISIBLE (-100 1450);
FORCEPROP 1 LAST BODY_TYPE PLUMBING
J 0
(-100 1500);
DISPLAY 0.872340 (-100 1500);
PAINT GREEN (-100 1500);
DISPLAY INVISIBLE (-100 1500);
FORCEPROP 1 LAST HDL_TAP TRUE
J 0
(225 1325);
DISPLAY 0.872340 (225 1325);
DISPLAY INVISIBLE (225 1325);
FORCEPROP 1 LAST PATH I64
J 0
(-102 1450);
DISPLAY 0.872340 (-102 1450);
PAINT GREEN (-102 1450);
DISPLAY INVISIBLE (-102 1450);
FORCEADD TAP..1
(-100 1500);
FORCEPROP 3 LASTPIN (-150 1500) SIG_NAME M_B_CPU0_SB_DQ<16>
J 0
(-140 1510);
DISPLAY 0.659574 (-140 1510);
PAINT MONO (-140 1510);
DISPLAY INVISIBLE (-140 1510);
FORCEPROP 1 LASTPIN (-150 1500) BN 16
J 0
(-162 1508);
DISPLAY 0.680851 (-162 1508);
PAINT GREEN (-162 1508);
FORCEPROP 2 LAST CDS_LIB standard
J 0
(-100 1500);
PAINT MONO (-100 1500);
DISPLAY INVISIBLE (-100 1500);
FORCEPROP 1 LAST BODY_TYPE PLUMBING
J 0
(-100 1550);
DISPLAY 0.872340 (-100 1550);
PAINT GREEN (-100 1550);
DISPLAY INVISIBLE (-100 1550);
FORCEPROP 1 LAST HDL_TAP TRUE
J 0
(225 1375);
DISPLAY 0.872340 (225 1375);
DISPLAY INVISIBLE (225 1375);
FORCEPROP 1 LAST PATH I65
J 0
(-102 1500);
DISPLAY 0.872340 (-102 1500);
PAINT GREEN (-102 1500);
DISPLAY INVISIBLE (-102 1500);
FORCEADD TAP..1
(-100 1550);
FORCEPROP 3 LASTPIN (-150 1550) SIG_NAME M_B_CPU0_SB_DQ<17>
J 0
(-140 1560);
DISPLAY 0.659574 (-140 1560);
PAINT MONO (-140 1560);
DISPLAY INVISIBLE (-140 1560);
FORCEPROP 1 LASTPIN (-150 1550) BN 17
J 0
(-162 1558);
DISPLAY 0.680851 (-162 1558);
PAINT GREEN (-162 1558);
FORCEPROP 2 LAST CDS_LIB standard
J 0
(-100 1550);
PAINT MONO (-100 1550);
DISPLAY INVISIBLE (-100 1550);
FORCEPROP 1 LAST BODY_TYPE PLUMBING
J 0
(-100 1600);
DISPLAY 0.872340 (-100 1600);
PAINT GREEN (-100 1600);
DISPLAY INVISIBLE (-100 1600);
FORCEPROP 1 LAST HDL_TAP TRUE
J 0
(225 1425);
DISPLAY 0.872340 (225 1425);
DISPLAY INVISIBLE (225 1425);
FORCEPROP 1 LAST PATH I66
J 0
(-102 1550);
DISPLAY 0.872340 (-102 1550);
PAINT GREEN (-102 1550);
DISPLAY INVISIBLE (-102 1550);
FORCEADD TAP..1
(-100 1600);
FORCEPROP 3 LASTPIN (-150 1600) SIG_NAME M_B_CPU0_SB_DQ<18>
J 0
(-140 1610);
DISPLAY 0.659574 (-140 1610);
PAINT MONO (-140 1610);
DISPLAY INVISIBLE (-140 1610);
FORCEPROP 1 LASTPIN (-150 1600) BN 18
J 0
(-162 1608);
DISPLAY 0.680851 (-162 1608);
PAINT GREEN (-162 1608);
FORCEPROP 2 LAST CDS_LIB standard
J 0
(-100 1600);
PAINT MONO (-100 1600);
DISPLAY INVISIBLE (-100 1600);
FORCEPROP 1 LAST BODY_TYPE PLUMBING
J 0
(-100 1650);
DISPLAY 0.872340 (-100 1650);
PAINT GREEN (-100 1650);
DISPLAY INVISIBLE (-100 1650);
FORCEPROP 1 LAST HDL_TAP TRUE
J 0
(225 1475);
DISPLAY 0.872340 (225 1475);
DISPLAY INVISIBLE (225 1475);
FORCEPROP 1 LAST PATH I67
J 0
(-102 1600);
DISPLAY 0.872340 (-102 1600);
PAINT GREEN (-102 1600);
DISPLAY INVISIBLE (-102 1600);
FORCEADD TAP..1
(-100 1650);
FORCEPROP 3 LASTPIN (-150 1650) SIG_NAME M_B_CPU0_SB_DQ<19>
J 0
(-140 1660);
DISPLAY 0.659574 (-140 1660);
PAINT MONO (-140 1660);
DISPLAY INVISIBLE (-140 1660);
FORCEPROP 1 LASTPIN (-150 1650) BN 19
J 0
(-162 1658);
DISPLAY 0.680851 (-162 1658);
PAINT GREEN (-162 1658);
FORCEPROP 2 LAST CDS_LIB standard
J 0
(-100 1650);
PAINT MONO (-100 1650);
DISPLAY INVISIBLE (-100 1650);
FORCEPROP 1 LAST BODY_TYPE PLUMBING
J 0
(-100 1700);
DISPLAY 0.872340 (-100 1700);
PAINT GREEN (-100 1700);
DISPLAY INVISIBLE (-100 1700);
FORCEPROP 1 LAST HDL_TAP TRUE
J 0
(225 1525);
DISPLAY 0.872340 (225 1525);
DISPLAY INVISIBLE (225 1525);
FORCEPROP 1 LAST PATH I68
J 0
(-102 1650);
DISPLAY 0.872340 (-102 1650);
PAINT GREEN (-102 1650);
DISPLAY INVISIBLE (-102 1650);
FORCEADD TAP..1
(-100 1750);
FORCEPROP 3 LASTPIN (-150 1750) SIG_NAME M_B_CPU0_SB_DQ<21>
J 0
(-140 1760);
DISPLAY 0.659574 (-140 1760);
PAINT MONO (-140 1760);
DISPLAY INVISIBLE (-140 1760);
FORCEPROP 1 LASTPIN (-150 1750) BN 21
J 0
(-162 1758);
DISPLAY 0.680851 (-162 1758);
PAINT GREEN (-162 1758);
FORCEPROP 2 LAST CDS_LIB standard
J 0
(-100 1750);
PAINT MONO (-100 1750);
DISPLAY INVISIBLE (-100 1750);
FORCEPROP 1 LAST BODY_TYPE PLUMBING
J 0
(-100 1800);
DISPLAY 0.872340 (-100 1800);
PAINT GREEN (-100 1800);
DISPLAY INVISIBLE (-100 1800);
FORCEPROP 1 LAST HDL_TAP TRUE
J 0
(225 1625);
DISPLAY 0.872340 (225 1625);
DISPLAY INVISIBLE (225 1625);
FORCEPROP 1 LAST PATH I69
J 0
(-102 1750);
DISPLAY 0.872340 (-102 1750);
PAINT GREEN (-102 1750);
DISPLAY INVISIBLE (-102 1750);
FORCEADD OFFPAGE..1
(-2600 1400);
FORCEPROP 2 LAST $XR0 84 
J 0
(-2851 1400);
DISPLAY 0.638298 (-2851 1400);
PAINT MONO (-2851 1400);
FORCEPROP 2 LAST CDS_LIB standard
J 0
(-2600 1400);
PAINT MONO (-2600 1400);
DISPLAY INVISIBLE (-2600 1400);
FORCEPROP 1 LAST OFFPAGE TRUE
J 0
(-2275 1275);
DISPLAY 0.872340 (-2275 1275);
DISPLAY INVISIBLE (-2275 1275);
FORCEPROP 1 LAST COMMENT_BODY TRUE
J 0
(-2475 1300);
DISPLAY 0.872340 (-2475 1300);
PAINT GREEN (-2475 1300);
DISPLAY INVISIBLE (-2475 1300);
FORCEPROP 2 LAST PATH I7
J 0
(-2550 1475);
DISPLAY 1.021277 (-2550 1475);
DISPLAY INVISIBLE (-2550 1475);
FORCEADD TAP..1
(-100 1700);
FORCEPROP 3 LASTPIN (-150 1700) SIG_NAME M_B_CPU0_SB_DQ<20>
J 0
(-140 1710);
DISPLAY 0.659574 (-140 1710);
PAINT MONO (-140 1710);
DISPLAY INVISIBLE (-140 1710);
FORCEPROP 1 LASTPIN (-150 1700) BN 20
J 0
(-162 1708);
DISPLAY 0.680851 (-162 1708);
PAINT GREEN (-162 1708);
FORCEPROP 2 LAST CDS_LIB standard
J 0
(-100 1700);
PAINT MONO (-100 1700);
DISPLAY INVISIBLE (-100 1700);
FORCEPROP 1 LAST BODY_TYPE PLUMBING
J 0
(-100 1750);
DISPLAY 0.872340 (-100 1750);
PAINT GREEN (-100 1750);
DISPLAY INVISIBLE (-100 1750);
FORCEPROP 1 LAST HDL_TAP TRUE
J 0
(225 1575);
DISPLAY 0.872340 (225 1575);
DISPLAY INVISIBLE (225 1575);
FORCEPROP 1 LAST PATH I70
J 0
(-102 1700);
DISPLAY 0.872340 (-102 1700);
PAINT GREEN (-102 1700);
DISPLAY INVISIBLE (-102 1700);
FORCEADD TAP..1
(-100 1850);
FORCEPROP 3 LASTPIN (-150 1850) SIG_NAME M_B_CPU0_SB_DQ<23>
J 0
(-140 1860);
DISPLAY 0.659574 (-140 1860);
PAINT MONO (-140 1860);
DISPLAY INVISIBLE (-140 1860);
FORCEPROP 1 LASTPIN (-150 1850) BN 23
J 0
(-162 1858);
DISPLAY 0.680851 (-162 1858);
PAINT GREEN (-162 1858);
FORCEPROP 2 LAST CDS_LIB standard
J 0
(-100 1850);
DISPLAY INVISIBLE (-100 1850);
FORCEPROP 1 LAST BODY_TYPE PLUMBING
J 0
(-100 1900);
DISPLAY 0.872340 (-100 1900);
PAINT GREEN (-100 1900);
DISPLAY INVISIBLE (-100 1900);
FORCEPROP 1 LAST HDL_TAP TRUE
J 0
(225 1725);
DISPLAY 0.872340 (225 1725);
DISPLAY INVISIBLE (225 1725);
FORCEPROP 1 LAST PATH I71
J 0
(-102 1850);
DISPLAY 0.872340 (-102 1850);
PAINT GREEN (-102 1850);
DISPLAY INVISIBLE (-102 1850);
FORCEADD TAP..1
(-100 1900);
FORCEPROP 3 LASTPIN (-150 1900) SIG_NAME M_B_CPU0_SB_DQ<24>
J 0
(-140 1910);
DISPLAY 0.659574 (-140 1910);
PAINT MONO (-140 1910);
DISPLAY INVISIBLE (-140 1910);
FORCEPROP 1 LASTPIN (-150 1900) BN 24
J 0
(-162 1908);
DISPLAY 0.680851 (-162 1908);
PAINT GREEN (-162 1908);
FORCEPROP 2 LAST CDS_LIB standard
J 0
(-100 1900);
DISPLAY INVISIBLE (-100 1900);
FORCEPROP 1 LAST BODY_TYPE PLUMBING
J 0
(-100 1950);
DISPLAY 0.872340 (-100 1950);
PAINT GREEN (-100 1950);
DISPLAY INVISIBLE (-100 1950);
FORCEPROP 1 LAST HDL_TAP TRUE
J 0
(225 1775);
DISPLAY 0.872340 (225 1775);
DISPLAY INVISIBLE (225 1775);
FORCEPROP 1 LAST PATH I72
J 0
(-102 1900);
DISPLAY 0.872340 (-102 1900);
PAINT GREEN (-102 1900);
DISPLAY INVISIBLE (-102 1900);
FORCEADD TAP..1
(-100 1800);
FORCEPROP 3 LASTPIN (-150 1800) SIG_NAME M_B_CPU0_SB_DQ<22>
J 0
(-140 1810);
DISPLAY 0.659574 (-140 1810);
PAINT MONO (-140 1810);
DISPLAY INVISIBLE (-140 1810);
FORCEPROP 1 LASTPIN (-150 1800) BN 22
J 0
(-162 1808);
DISPLAY 0.680851 (-162 1808);
PAINT GREEN (-162 1808);
FORCEPROP 2 LAST CDS_LIB standard
J 0
(-100 1800);
DISPLAY INVISIBLE (-100 1800);
FORCEPROP 1 LAST BODY_TYPE PLUMBING
J 0
(-100 1850);
DISPLAY 0.872340 (-100 1850);
PAINT GREEN (-100 1850);
DISPLAY INVISIBLE (-100 1850);
FORCEPROP 1 LAST HDL_TAP TRUE
J 0
(225 1675);
DISPLAY 0.872340 (225 1675);
DISPLAY INVISIBLE (225 1675);
FORCEPROP 1 LAST PATH I73
J 0
(-102 1800);
DISPLAY 0.872340 (-102 1800);
PAINT GREEN (-102 1800);
DISPLAY INVISIBLE (-102 1800);
FORCEADD TAP..1
(-100 1950);
FORCEPROP 3 LASTPIN (-150 1950) SIG_NAME M_B_CPU0_SB_DQ<25>
J 0
(-140 1960);
DISPLAY 0.659574 (-140 1960);
PAINT MONO (-140 1960);
DISPLAY INVISIBLE (-140 1960);
FORCEPROP 1 LASTPIN (-150 1950) BN 25
J 0
(-162 1958);
DISPLAY 0.680851 (-162 1958);
PAINT GREEN (-162 1958);
FORCEPROP 2 LAST CDS_LIB standard
J 0
(-100 1950);
DISPLAY INVISIBLE (-100 1950);
FORCEPROP 1 LAST BODY_TYPE PLUMBING
J 0
(-100 2000);
DISPLAY 0.872340 (-100 2000);
PAINT GREEN (-100 2000);
DISPLAY INVISIBLE (-100 2000);
FORCEPROP 1 LAST HDL_TAP TRUE
J 0
(225 1825);
DISPLAY 0.872340 (225 1825);
DISPLAY INVISIBLE (225 1825);
FORCEPROP 1 LAST PATH I74
J 0
(-102 1950);
DISPLAY 0.872340 (-102 1950);
PAINT GREEN (-102 1950);
DISPLAY INVISIBLE (-102 1950);
FORCEADD TAP..1
(-100 2000);
FORCEPROP 3 LASTPIN (-150 2000) SIG_NAME M_B_CPU0_SB_DQ<26>
J 0
(-140 2010);
DISPLAY 0.659574 (-140 2010);
PAINT MONO (-140 2010);
DISPLAY INVISIBLE (-140 2010);
FORCEPROP 1 LASTPIN (-150 2000) BN 26
J 0
(-162 2008);
DISPLAY 0.680851 (-162 2008);
PAINT GREEN (-162 2008);
FORCEPROP 2 LAST CDS_LIB standard
J 0
(-100 2000);
DISPLAY INVISIBLE (-100 2000);
FORCEPROP 1 LAST BODY_TYPE PLUMBING
J 0
(-100 2050);
DISPLAY 0.872340 (-100 2050);
PAINT GREEN (-100 2050);
DISPLAY INVISIBLE (-100 2050);
FORCEPROP 1 LAST HDL_TAP TRUE
J 0
(225 1875);
DISPLAY 0.872340 (225 1875);
DISPLAY INVISIBLE (225 1875);
FORCEPROP 1 LAST PATH I75
J 0
(-102 2000);
DISPLAY 0.872340 (-102 2000);
PAINT GREEN (-102 2000);
DISPLAY INVISIBLE (-102 2000);
FORCEADD TAP..1
(-100 2050);
FORCEPROP 3 LASTPIN (-150 2050) SIG_NAME M_B_CPU0_SB_DQ<27>
J 0
(-140 2060);
DISPLAY 0.659574 (-140 2060);
PAINT MONO (-140 2060);
DISPLAY INVISIBLE (-140 2060);
FORCEPROP 1 LASTPIN (-150 2050) BN 27
J 0
(-162 2058);
DISPLAY 0.680851 (-162 2058);
PAINT GREEN (-162 2058);
FORCEPROP 2 LAST CDS_LIB standard
J 0
(-100 2050);
DISPLAY INVISIBLE (-100 2050);
FORCEPROP 1 LAST BODY_TYPE PLUMBING
J 0
(-100 2100);
DISPLAY 0.872340 (-100 2100);
PAINT GREEN (-100 2100);
DISPLAY INVISIBLE (-100 2100);
FORCEPROP 1 LAST HDL_TAP TRUE
J 0
(225 1925);
DISPLAY 0.872340 (225 1925);
DISPLAY INVISIBLE (225 1925);
FORCEPROP 1 LAST PATH I76
J 0
(-102 2050);
DISPLAY 0.872340 (-102 2050);
PAINT GREEN (-102 2050);
DISPLAY INVISIBLE (-102 2050);
FORCEADD TAP..1
(-100 2100);
FORCEPROP 3 LASTPIN (-150 2100) SIG_NAME M_B_CPU0_SB_DQ<28>
J 0
(-140 2110);
DISPLAY 0.659574 (-140 2110);
PAINT MONO (-140 2110);
DISPLAY INVISIBLE (-140 2110);
FORCEPROP 1 LASTPIN (-150 2100) BN 28
J 0
(-162 2108);
DISPLAY 0.680851 (-162 2108);
PAINT GREEN (-162 2108);
FORCEPROP 2 LAST CDS_LIB standard
J 0
(-100 2100);
DISPLAY INVISIBLE (-100 2100);
FORCEPROP 1 LAST BODY_TYPE PLUMBING
J 0
(-100 2150);
DISPLAY 0.872340 (-100 2150);
PAINT GREEN (-100 2150);
DISPLAY INVISIBLE (-100 2150);
FORCEPROP 1 LAST HDL_TAP TRUE
J 0
(225 1975);
DISPLAY 0.872340 (225 1975);
DISPLAY INVISIBLE (225 1975);
FORCEPROP 1 LAST PATH I77
J 0
(-102 2100);
DISPLAY 0.872340 (-102 2100);
PAINT GREEN (-102 2100);
DISPLAY INVISIBLE (-102 2100);
FORCEADD TAP..1
(-100 2150);
FORCEPROP 3 LASTPIN (-150 2150) SIG_NAME M_B_CPU0_SB_DQ<29>
J 0
(-140 2160);
DISPLAY 0.659574 (-140 2160);
PAINT MONO (-140 2160);
DISPLAY INVISIBLE (-140 2160);
FORCEPROP 1 LASTPIN (-150 2150) BN 29
J 0
(-162 2158);
DISPLAY 0.680851 (-162 2158);
PAINT GREEN (-162 2158);
FORCEPROP 2 LAST CDS_LIB standard
J 0
(-100 2150);
DISPLAY INVISIBLE (-100 2150);
FORCEPROP 1 LAST BODY_TYPE PLUMBING
J 0
(-100 2200);
DISPLAY 0.872340 (-100 2200);
PAINT GREEN (-100 2200);
DISPLAY INVISIBLE (-100 2200);
FORCEPROP 1 LAST HDL_TAP TRUE
J 0
(225 2025);
DISPLAY 0.872340 (225 2025);
DISPLAY INVISIBLE (225 2025);
FORCEPROP 1 LAST PATH I78
J 0
(-102 2150);
DISPLAY 0.872340 (-102 2150);
PAINT GREEN (-102 2150);
DISPLAY INVISIBLE (-102 2150);
FORCEADD TAP..1
(-100 2250);
FORCEPROP 3 LASTPIN (-150 2250) SIG_NAME M_B_CPU0_SB_DQ<31>
J 0
(-140 2260);
DISPLAY 0.659574 (-140 2260);
PAINT MONO (-140 2260);
DISPLAY INVISIBLE (-140 2260);
FORCEPROP 1 LASTPIN (-150 2250) BN 31
J 0
(-162 2258);
DISPLAY 0.680851 (-162 2258);
PAINT GREEN (-162 2258);
FORCEPROP 2 LAST CDS_LIB standard
J 0
(-100 2250);
DISPLAY INVISIBLE (-100 2250);
FORCEPROP 1 LAST BODY_TYPE PLUMBING
J 0
(-100 2300);
DISPLAY 0.872340 (-100 2300);
PAINT GREEN (-100 2300);
DISPLAY INVISIBLE (-100 2300);
FORCEPROP 1 LAST HDL_TAP TRUE
J 0
(225 2125);
DISPLAY 0.872340 (225 2125);
DISPLAY INVISIBLE (225 2125);
FORCEPROP 1 LAST PATH I79
J 0
(-102 2250);
DISPLAY 0.872340 (-102 2250);
PAINT GREEN (-102 2250);
DISPLAY INVISIBLE (-102 2250);
FORCEADD OFFPAGE..1
(-2675 1650);
FORCEPROP 2 LAST $XR3 85 
J 0
(-2927 1614);
DISPLAY 0.638298 (-2927 1614);
PAINT MONO (-2927 1614);
FORCEPROP 2 LAST $XR2 83 
J 0
(-3107 1650);
DISPLAY 0.638298 (-3107 1650);
PAINT MONO (-3107 1650);
FORCEPROP 2 LAST $XR1 82 
J 0
(-3017 1650);
DISPLAY 0.638298 (-3017 1650);
PAINT MONO (-3017 1650);
FORCEPROP 2 LAST $XR0 129 
J 0
(-2927 1650);
DISPLAY 0.638298 (-2927 1650);
PAINT MONO (-2927 1650);
FORCEPROP 2 LAST CDS_LIB standard
J 0
(-2675 1650);
PAINT MONO (-2675 1650);
DISPLAY INVISIBLE (-2675 1650);
FORCEPROP 1 LAST OFFPAGE TRUE
J 0
(-2350 1525);
DISPLAY 0.872340 (-2350 1525);
DISPLAY INVISIBLE (-2350 1525);
FORCEPROP 1 LAST COMMENT_BODY TRUE
J 0
(-2550 1550);
DISPLAY 0.872340 (-2550 1550);
PAINT GREEN (-2550 1550);
DISPLAY INVISIBLE (-2550 1550);
FORCEPROP 2 LAST PATH I8
J 0
(-2625 1725);
DISPLAY 1.021277 (-2625 1725);
DISPLAY INVISIBLE (-2625 1725);
FORCEADD TAP..1
(-100 2200);
FORCEPROP 3 LASTPIN (-150 2200) SIG_NAME M_B_CPU0_SB_DQ<30>
J 0
(-140 2210);
DISPLAY 0.659574 (-140 2210);
PAINT MONO (-140 2210);
DISPLAY INVISIBLE (-140 2210);
FORCEPROP 1 LASTPIN (-150 2200) BN 30
J 0
(-162 2208);
DISPLAY 0.680851 (-162 2208);
PAINT GREEN (-162 2208);
FORCEPROP 2 LAST CDS_LIB standard
J 0
(-100 2200);
DISPLAY INVISIBLE (-100 2200);
FORCEPROP 1 LAST BODY_TYPE PLUMBING
J 0
(-100 2250);
DISPLAY 0.872340 (-100 2250);
PAINT GREEN (-100 2250);
DISPLAY INVISIBLE (-100 2250);
FORCEPROP 1 LAST HDL_TAP TRUE
J 0
(225 2075);
DISPLAY 0.872340 (225 2075);
DISPLAY INVISIBLE (225 2075);
FORCEPROP 1 LAST PATH I80
J 0
(-102 2200);
DISPLAY 0.872340 (-102 2200);
PAINT GREEN (-102 2200);
DISPLAY INVISIBLE (-102 2200);
FORCEADD TAP..1
(-100 2350);
FORCEPROP 3 LASTPIN (-150 2350) SIG_NAME M_B_CPU0_SA_DQ<0>
J 0
(-140 2360);
DISPLAY 0.659574 (-140 2360);
PAINT MONO (-140 2360);
DISPLAY INVISIBLE (-140 2360);
FORCEPROP 1 LASTPIN (-150 2350) BN 0
J 0
(-162 2358);
DISPLAY 0.680851 (-162 2358);
PAINT GREEN (-162 2358);
FORCEPROP 2 LAST CDS_LIB standard
J 0
(-100 2350);
PAINT MONO (-100 2350);
DISPLAY INVISIBLE (-100 2350);
FORCEPROP 1 LAST BODY_TYPE PLUMBING
J 0
(-100 2400);
DISPLAY 0.872340 (-100 2400);
PAINT GREEN (-100 2400);
DISPLAY INVISIBLE (-100 2400);
FORCEPROP 1 LAST HDL_TAP TRUE
J 0
(225 2225);
DISPLAY 0.872340 (225 2225);
DISPLAY INVISIBLE (225 2225);
FORCEPROP 1 LAST PATH I81
J 0
(-102 2350);
DISPLAY 0.872340 (-102 2350);
PAINT GREEN (-102 2350);
DISPLAY INVISIBLE (-102 2350);
FORCEADD TAP..1
(-100 2400);
FORCEPROP 3 LASTPIN (-150 2400) SIG_NAME M_B_CPU0_SA_DQ<1>
J 0
(-140 2410);
DISPLAY 0.659574 (-140 2410);
PAINT MONO (-140 2410);
DISPLAY INVISIBLE (-140 2410);
FORCEPROP 1 LASTPIN (-150 2400) BN 1
J 0
(-162 2408);
DISPLAY 0.680851 (-162 2408);
PAINT GREEN (-162 2408);
FORCEPROP 2 LAST CDS_LIB standard
J 0
(-100 2400);
PAINT MONO (-100 2400);
DISPLAY INVISIBLE (-100 2400);
FORCEPROP 1 LAST BODY_TYPE PLUMBING
J 0
(-100 2450);
DISPLAY 0.872340 (-100 2450);
PAINT GREEN (-100 2450);
DISPLAY INVISIBLE (-100 2450);
FORCEPROP 1 LAST HDL_TAP TRUE
J 0
(225 2275);
DISPLAY 0.872340 (225 2275);
DISPLAY INVISIBLE (225 2275);
FORCEPROP 1 LAST PATH I82
J 0
(-102 2400);
DISPLAY 0.872340 (-102 2400);
PAINT GREEN (-102 2400);
DISPLAY INVISIBLE (-102 2400);
FORCEADD TAP..1
(-100 2450);
FORCEPROP 3 LASTPIN (-150 2450) SIG_NAME M_B_CPU0_SA_DQ<2>
J 0
(-140 2460);
DISPLAY 0.659574 (-140 2460);
PAINT MONO (-140 2460);
DISPLAY INVISIBLE (-140 2460);
FORCEPROP 1 LASTPIN (-150 2450) BN 2
J 0
(-162 2458);
DISPLAY 0.680851 (-162 2458);
PAINT GREEN (-162 2458);
FORCEPROP 2 LAST CDS_LIB standard
J 0
(-100 2450);
PAINT MONO (-100 2450);
DISPLAY INVISIBLE (-100 2450);
FORCEPROP 1 LAST BODY_TYPE PLUMBING
J 0
(-100 2500);
DISPLAY 0.872340 (-100 2500);
PAINT GREEN (-100 2500);
DISPLAY INVISIBLE (-100 2500);
FORCEPROP 1 LAST HDL_TAP TRUE
J 0
(225 2325);
DISPLAY 0.872340 (225 2325);
DISPLAY INVISIBLE (225 2325);
FORCEPROP 1 LAST PATH I83
J 0
(-102 2450);
DISPLAY 0.872340 (-102 2450);
PAINT GREEN (-102 2450);
DISPLAY INVISIBLE (-102 2450);
FORCEADD TAP..1
(-100 2500);
FORCEPROP 3 LASTPIN (-150 2500) SIG_NAME M_B_CPU0_SA_DQ<3>
J 0
(-140 2510);
DISPLAY 0.659574 (-140 2510);
PAINT MONO (-140 2510);
DISPLAY INVISIBLE (-140 2510);
FORCEPROP 1 LASTPIN (-150 2500) BN 3
J 0
(-162 2508);
DISPLAY 0.680851 (-162 2508);
PAINT GREEN (-162 2508);
FORCEPROP 2 LAST CDS_LIB standard
J 0
(-100 2500);
PAINT MONO (-100 2500);
DISPLAY INVISIBLE (-100 2500);
FORCEPROP 1 LAST BODY_TYPE PLUMBING
J 0
(-100 2550);
DISPLAY 0.872340 (-100 2550);
PAINT GREEN (-100 2550);
DISPLAY INVISIBLE (-100 2550);
FORCEPROP 1 LAST HDL_TAP TRUE
J 0
(225 2375);
DISPLAY 0.872340 (225 2375);
DISPLAY INVISIBLE (225 2375);
FORCEPROP 1 LAST PATH I84
J 0
(-102 2500);
DISPLAY 0.872340 (-102 2500);
PAINT GREEN (-102 2500);
DISPLAY INVISIBLE (-102 2500);
FORCEADD TAP..1
(-100 2550);
FORCEPROP 3 LASTPIN (-150 2550) SIG_NAME M_B_CPU0_SA_DQ<4>
J 0
(-140 2560);
DISPLAY 0.659574 (-140 2560);
PAINT MONO (-140 2560);
DISPLAY INVISIBLE (-140 2560);
FORCEPROP 1 LASTPIN (-150 2550) BN 4
J 0
(-162 2558);
DISPLAY 0.680851 (-162 2558);
PAINT GREEN (-162 2558);
FORCEPROP 2 LAST CDS_LIB standard
J 0
(-100 2550);
PAINT MONO (-100 2550);
DISPLAY INVISIBLE (-100 2550);
FORCEPROP 1 LAST BODY_TYPE PLUMBING
J 0
(-100 2600);
DISPLAY 0.872340 (-100 2600);
PAINT GREEN (-100 2600);
DISPLAY INVISIBLE (-100 2600);
FORCEPROP 1 LAST HDL_TAP TRUE
J 0
(225 2425);
DISPLAY 0.872340 (225 2425);
DISPLAY INVISIBLE (225 2425);
FORCEPROP 1 LAST PATH I85
J 0
(-102 2550);
DISPLAY 0.872340 (-102 2550);
PAINT GREEN (-102 2550);
DISPLAY INVISIBLE (-102 2550);
FORCEADD TAP..1
(-100 2600);
FORCEPROP 3 LASTPIN (-150 2600) SIG_NAME M_B_CPU0_SA_DQ<5>
J 0
(-140 2610);
DISPLAY 0.659574 (-140 2610);
PAINT MONO (-140 2610);
DISPLAY INVISIBLE (-140 2610);
FORCEPROP 1 LASTPIN (-150 2600) BN 5
J 0
(-162 2608);
DISPLAY 0.680851 (-162 2608);
PAINT GREEN (-162 2608);
FORCEPROP 2 LAST CDS_LIB standard
J 0
(-100 2600);
PAINT MONO (-100 2600);
DISPLAY INVISIBLE (-100 2600);
FORCEPROP 1 LAST BODY_TYPE PLUMBING
J 0
(-100 2650);
DISPLAY 0.872340 (-100 2650);
PAINT GREEN (-100 2650);
DISPLAY INVISIBLE (-100 2650);
FORCEPROP 1 LAST HDL_TAP TRUE
J 0
(225 2475);
DISPLAY 0.872340 (225 2475);
DISPLAY INVISIBLE (225 2475);
FORCEPROP 1 LAST PATH I86
J 0
(-102 2600);
DISPLAY 0.872340 (-102 2600);
PAINT GREEN (-102 2600);
DISPLAY INVISIBLE (-102 2600);
FORCEADD TAP..1
(-100 2650);
FORCEPROP 3 LASTPIN (-150 2650) SIG_NAME M_B_CPU0_SA_DQ<6>
J 0
(-140 2660);
DISPLAY 0.659574 (-140 2660);
PAINT MONO (-140 2660);
DISPLAY INVISIBLE (-140 2660);
FORCEPROP 1 LASTPIN (-150 2650) BN 6
J 0
(-162 2658);
DISPLAY 0.680851 (-162 2658);
PAINT GREEN (-162 2658);
FORCEPROP 2 LAST CDS_LIB standard
J 0
(-100 2650);
PAINT MONO (-100 2650);
DISPLAY INVISIBLE (-100 2650);
FORCEPROP 1 LAST BODY_TYPE PLUMBING
J 0
(-100 2700);
DISPLAY 0.872340 (-100 2700);
PAINT GREEN (-100 2700);
DISPLAY INVISIBLE (-100 2700);
FORCEPROP 1 LAST HDL_TAP TRUE
J 0
(225 2525);
DISPLAY 0.872340 (225 2525);
DISPLAY INVISIBLE (225 2525);
FORCEPROP 1 LAST PATH I87
J 0
(-102 2650);
DISPLAY 0.872340 (-102 2650);
PAINT GREEN (-102 2650);
DISPLAY INVISIBLE (-102 2650);
FORCEADD TAP..1
(-100 2750);
FORCEPROP 3 LASTPIN (-150 2750) SIG_NAME M_B_CPU0_SA_DQ<8>
J 0
(-140 2760);
DISPLAY 0.659574 (-140 2760);
PAINT MONO (-140 2760);
DISPLAY INVISIBLE (-140 2760);
FORCEPROP 1 LASTPIN (-150 2750) BN 8
J 0
(-162 2758);
DISPLAY 0.680851 (-162 2758);
PAINT GREEN (-162 2758);
FORCEPROP 2 LAST CDS_LIB standard
J 0
(-100 2750);
PAINT MONO (-100 2750);
DISPLAY INVISIBLE (-100 2750);
FORCEPROP 1 LAST BODY_TYPE PLUMBING
J 0
(-100 2800);
DISPLAY 0.872340 (-100 2800);
PAINT GREEN (-100 2800);
DISPLAY INVISIBLE (-100 2800);
FORCEPROP 1 LAST HDL_TAP TRUE
J 0
(225 2625);
DISPLAY 0.872340 (225 2625);
DISPLAY INVISIBLE (225 2625);
FORCEPROP 1 LAST PATH I88
J 0
(-102 2750);
DISPLAY 0.872340 (-102 2750);
PAINT GREEN (-102 2750);
DISPLAY INVISIBLE (-102 2750);
FORCEADD TAP..1
(-100 2700);
FORCEPROP 3 LASTPIN (-150 2700) SIG_NAME M_B_CPU0_SA_DQ<7>
J 0
(-140 2710);
DISPLAY 0.659574 (-140 2710);
PAINT MONO (-140 2710);
DISPLAY INVISIBLE (-140 2710);
FORCEPROP 1 LASTPIN (-150 2700) BN 7
J 0
(-162 2708);
DISPLAY 0.680851 (-162 2708);
PAINT GREEN (-162 2708);
FORCEPROP 2 LAST CDS_LIB standard
J 0
(-100 2700);
PAINT MONO (-100 2700);
DISPLAY INVISIBLE (-100 2700);
FORCEPROP 1 LAST BODY_TYPE PLUMBING
J 0
(-100 2750);
DISPLAY 0.872340 (-100 2750);
PAINT GREEN (-100 2750);
DISPLAY INVISIBLE (-100 2750);
FORCEPROP 1 LAST HDL_TAP TRUE
J 0
(225 2575);
DISPLAY 0.872340 (225 2575);
DISPLAY INVISIBLE (225 2575);
FORCEPROP 1 LAST PATH I89
J 0
(-102 2700);
DISPLAY 0.872340 (-102 2700);
PAINT GREEN (-102 2700);
DISPLAY INVISIBLE (-102 2700);
FORCEADD OFFPAGE..1
(-2675 1550);
FORCEPROP 2 LAST $XR1 85 
J 0
(-2986 1550);
DISPLAY 0.638298 (-2986 1550);
PAINT MONO (-2986 1550);
FORCEPROP 2 LAST $XR0 21 
J 0
(-2896 1550);
DISPLAY 0.638298 (-2896 1550);
PAINT MONO (-2896 1550);
FORCEPROP 2 LAST CDS_LIB standard
J 0
(-2675 1550);
PAINT MONO (-2675 1550);
DISPLAY INVISIBLE (-2675 1550);
FORCEPROP 1 LAST OFFPAGE TRUE
J 0
(-2350 1425);
DISPLAY 0.872340 (-2350 1425);
DISPLAY INVISIBLE (-2350 1425);
FORCEPROP 1 LAST COMMENT_BODY TRUE
J 0
(-2550 1450);
DISPLAY 0.872340 (-2550 1450);
PAINT GREEN (-2550 1450);
DISPLAY INVISIBLE (-2550 1450);
FORCEPROP 2 LAST PATH I9
J 0
(-2625 1625);
DISPLAY 1.021277 (-2625 1625);
DISPLAY INVISIBLE (-2625 1625);
FORCEADD TAP..1
(-100 2800);
FORCEPROP 3 LASTPIN (-150 2800) SIG_NAME M_B_CPU0_SA_DQ<9>
J 0
(-140 2810);
DISPLAY 0.659574 (-140 2810);
PAINT MONO (-140 2810);
DISPLAY INVISIBLE (-140 2810);
FORCEPROP 1 LASTPIN (-150 2800) BN 9
J 0
(-162 2808);
DISPLAY 0.680851 (-162 2808);
PAINT GREEN (-162 2808);
FORCEPROP 2 LAST CDS_LIB standard
J 0
(-100 2800);
PAINT MONO (-100 2800);
DISPLAY INVISIBLE (-100 2800);
FORCEPROP 1 LAST BODY_TYPE PLUMBING
J 0
(-100 2850);
DISPLAY 0.872340 (-100 2850);
PAINT GREEN (-100 2850);
DISPLAY INVISIBLE (-100 2850);
FORCEPROP 1 LAST HDL_TAP TRUE
J 0
(225 2675);
DISPLAY 0.872340 (225 2675);
DISPLAY INVISIBLE (225 2675);
FORCEPROP 1 LAST PATH I90
J 0
(-102 2800);
DISPLAY 0.872340 (-102 2800);
PAINT GREEN (-102 2800);
DISPLAY INVISIBLE (-102 2800);
FORCEADD TAP..1
(-100 2900);
FORCEPROP 3 LASTPIN (-150 2900) SIG_NAME M_B_CPU0_SA_DQ<11>
J 0
(-140 2910);
DISPLAY 0.659574 (-140 2910);
PAINT MONO (-140 2910);
DISPLAY INVISIBLE (-140 2910);
FORCEPROP 1 LASTPIN (-150 2900) BN 11
J 0
(-162 2908);
DISPLAY 0.680851 (-162 2908);
PAINT GREEN (-162 2908);
FORCEPROP 2 LAST CDS_LIB standard
J 0
(-100 2900);
PAINT MONO (-100 2900);
DISPLAY INVISIBLE (-100 2900);
FORCEPROP 1 LAST BODY_TYPE PLUMBING
J 0
(-100 2950);
DISPLAY 0.872340 (-100 2950);
PAINT GREEN (-100 2950);
DISPLAY INVISIBLE (-100 2950);
FORCEPROP 1 LAST HDL_TAP TRUE
J 0
(225 2775);
DISPLAY 0.872340 (225 2775);
DISPLAY INVISIBLE (225 2775);
FORCEPROP 1 LAST PATH I91
J 0
(-102 2900);
DISPLAY 0.872340 (-102 2900);
PAINT GREEN (-102 2900);
DISPLAY INVISIBLE (-102 2900);
FORCEADD TAP..1
(-100 2850);
FORCEPROP 3 LASTPIN (-150 2850) SIG_NAME M_B_CPU0_SA_DQ<10>
J 0
(-140 2860);
DISPLAY 0.659574 (-140 2860);
PAINT MONO (-140 2860);
DISPLAY INVISIBLE (-140 2860);
FORCEPROP 1 LASTPIN (-150 2850) BN 10
J 0
(-162 2858);
DISPLAY 0.680851 (-162 2858);
PAINT GREEN (-162 2858);
FORCEPROP 2 LAST CDS_LIB standard
J 0
(-100 2850);
PAINT MONO (-100 2850);
DISPLAY INVISIBLE (-100 2850);
FORCEPROP 1 LAST BODY_TYPE PLUMBING
J 0
(-100 2900);
DISPLAY 0.872340 (-100 2900);
PAINT GREEN (-100 2900);
DISPLAY INVISIBLE (-100 2900);
FORCEPROP 1 LAST HDL_TAP TRUE
J 0
(225 2725);
DISPLAY 0.872340 (225 2725);
DISPLAY INVISIBLE (225 2725);
FORCEPROP 1 LAST PATH I92
J 0
(-102 2850);
DISPLAY 0.872340 (-102 2850);
PAINT GREEN (-102 2850);
DISPLAY INVISIBLE (-102 2850);
FORCEADD TAP..1
(-100 3000);
FORCEPROP 3 LASTPIN (-150 3000) SIG_NAME M_B_CPU0_SA_DQ<13>
J 0
(-140 3010);
DISPLAY 0.659574 (-140 3010);
PAINT MONO (-140 3010);
DISPLAY INVISIBLE (-140 3010);
FORCEPROP 1 LASTPIN (-150 3000) BN 13
J 0
(-162 3008);
DISPLAY 0.680851 (-162 3008);
PAINT GREEN (-162 3008);
FORCEPROP 2 LAST CDS_LIB standard
J 0
(-100 3000);
PAINT MONO (-100 3000);
DISPLAY INVISIBLE (-100 3000);
FORCEPROP 1 LAST BODY_TYPE PLUMBING
J 0
(-100 3050);
DISPLAY 0.872340 (-100 3050);
PAINT GREEN (-100 3050);
DISPLAY INVISIBLE (-100 3050);
FORCEPROP 1 LAST HDL_TAP TRUE
J 0
(225 2875);
DISPLAY 0.872340 (225 2875);
DISPLAY INVISIBLE (225 2875);
FORCEPROP 1 LAST PATH I93
J 0
(-102 3000);
DISPLAY 0.872340 (-102 3000);
PAINT GREEN (-102 3000);
DISPLAY INVISIBLE (-102 3000);
FORCEADD TAP..1
(-100 3050);
FORCEPROP 3 LASTPIN (-150 3050) SIG_NAME M_B_CPU0_SA_DQ<14>
J 0
(-140 3060);
DISPLAY 0.659574 (-140 3060);
PAINT MONO (-140 3060);
DISPLAY INVISIBLE (-140 3060);
FORCEPROP 1 LASTPIN (-150 3050) BN 14
J 0
(-162 3058);
DISPLAY 0.680851 (-162 3058);
PAINT GREEN (-162 3058);
FORCEPROP 2 LAST CDS_LIB standard
J 0
(-100 3050);
PAINT MONO (-100 3050);
DISPLAY INVISIBLE (-100 3050);
FORCEPROP 1 LAST BODY_TYPE PLUMBING
J 0
(-100 3100);
DISPLAY 0.872340 (-100 3100);
PAINT GREEN (-100 3100);
DISPLAY INVISIBLE (-100 3100);
FORCEPROP 1 LAST HDL_TAP TRUE
J 0
(225 2925);
DISPLAY 0.872340 (225 2925);
DISPLAY INVISIBLE (225 2925);
FORCEPROP 1 LAST PATH I94
J 0
(-102 3050);
DISPLAY 0.872340 (-102 3050);
PAINT GREEN (-102 3050);
DISPLAY INVISIBLE (-102 3050);
FORCEADD TAP..1
(-100 2950);
FORCEPROP 3 LASTPIN (-150 2950) SIG_NAME M_B_CPU0_SA_DQ<12>
J 0
(-140 2960);
DISPLAY 0.659574 (-140 2960);
PAINT MONO (-140 2960);
DISPLAY INVISIBLE (-140 2960);
FORCEPROP 1 LASTPIN (-150 2950) BN 12
J 0
(-162 2958);
DISPLAY 0.680851 (-162 2958);
PAINT GREEN (-162 2958);
FORCEPROP 2 LAST CDS_LIB standard
J 0
(-100 2950);
PAINT MONO (-100 2950);
DISPLAY INVISIBLE (-100 2950);
FORCEPROP 1 LAST BODY_TYPE PLUMBING
J 0
(-100 3000);
DISPLAY 0.872340 (-100 3000);
PAINT GREEN (-100 3000);
DISPLAY INVISIBLE (-100 3000);
FORCEPROP 1 LAST HDL_TAP TRUE
J 0
(225 2825);
DISPLAY 0.872340 (225 2825);
DISPLAY INVISIBLE (225 2825);
FORCEPROP 1 LAST PATH I95
J 0
(-102 2950);
DISPLAY 0.872340 (-102 2950);
PAINT GREEN (-102 2950);
DISPLAY INVISIBLE (-102 2950);
FORCEADD TAP..1
(-100 3150);
FORCEPROP 3 LASTPIN (-150 3150) SIG_NAME M_B_CPU0_SA_DQ<16>
J 0
(-140 3160);
DISPLAY 0.659574 (-140 3160);
PAINT MONO (-140 3160);
DISPLAY INVISIBLE (-140 3160);
FORCEPROP 1 LASTPIN (-150 3150) BN 16
J 0
(-162 3158);
DISPLAY 0.680851 (-162 3158);
PAINT GREEN (-162 3158);
FORCEPROP 2 LAST CDS_LIB standard
J 0
(-100 3150);
PAINT MONO (-100 3150);
DISPLAY INVISIBLE (-100 3150);
FORCEPROP 1 LAST BODY_TYPE PLUMBING
J 0
(-100 3200);
DISPLAY 0.872340 (-100 3200);
PAINT GREEN (-100 3200);
DISPLAY INVISIBLE (-100 3200);
FORCEPROP 1 LAST HDL_TAP TRUE
J 0
(225 3025);
DISPLAY 0.872340 (225 3025);
DISPLAY INVISIBLE (225 3025);
FORCEPROP 1 LAST PATH I96
J 0
(-102 3150);
DISPLAY 0.872340 (-102 3150);
PAINT GREEN (-102 3150);
DISPLAY INVISIBLE (-102 3150);
FORCEADD TAP..1
(-100 3100);
FORCEPROP 3 LASTPIN (-150 3100) SIG_NAME M_B_CPU0_SA_DQ<15>
J 0
(-140 3110);
DISPLAY 0.659574 (-140 3110);
PAINT MONO (-140 3110);
DISPLAY INVISIBLE (-140 3110);
FORCEPROP 1 LASTPIN (-150 3100) BN 15
J 0
(-162 3108);
DISPLAY 0.680851 (-162 3108);
PAINT GREEN (-162 3108);
FORCEPROP 2 LAST CDS_LIB standard
J 0
(-100 3100);
PAINT MONO (-100 3100);
DISPLAY INVISIBLE (-100 3100);
FORCEPROP 1 LAST BODY_TYPE PLUMBING
J 0
(-100 3150);
DISPLAY 0.872340 (-100 3150);
PAINT GREEN (-100 3150);
DISPLAY INVISIBLE (-100 3150);
FORCEPROP 1 LAST HDL_TAP TRUE
J 0
(225 2975);
DISPLAY 0.872340 (225 2975);
DISPLAY INVISIBLE (225 2975);
FORCEPROP 1 LAST PATH I97
J 0
(-102 3100);
DISPLAY 0.872340 (-102 3100);
PAINT GREEN (-102 3100);
DISPLAY INVISIBLE (-102 3100);
FORCEADD TAP..1
(-100 3300);
FORCEPROP 3 LASTPIN (-150 3300) SIG_NAME M_B_CPU0_SA_DQ<19>
J 0
(-140 3310);
DISPLAY 0.659574 (-140 3310);
PAINT MONO (-140 3310);
DISPLAY INVISIBLE (-140 3310);
FORCEPROP 1 LASTPIN (-150 3300) BN 19
J 0
(-162 3308);
DISPLAY 0.680851 (-162 3308);
PAINT GREEN (-162 3308);
FORCEPROP 2 LAST CDS_LIB standard
J 0
(-100 3300);
PAINT MONO (-100 3300);
DISPLAY INVISIBLE (-100 3300);
FORCEPROP 1 LAST BODY_TYPE PLUMBING
J 0
(-100 3350);
DISPLAY 0.872340 (-100 3350);
PAINT GREEN (-100 3350);
DISPLAY INVISIBLE (-100 3350);
FORCEPROP 1 LAST HDL_TAP TRUE
J 0
(225 3175);
DISPLAY 0.872340 (225 3175);
DISPLAY INVISIBLE (225 3175);
FORCEPROP 1 LAST PATH I98
J 0
(-102 3300);
DISPLAY 0.872340 (-102 3300);
PAINT GREEN (-102 3300);
DISPLAY INVISIBLE (-102 3300);
FORCEADD TAP..1
(-100 3250);
FORCEPROP 3 LASTPIN (-150 3250) SIG_NAME M_B_CPU0_SA_DQ<18>
J 0
(-140 3260);
DISPLAY 0.659574 (-140 3260);
PAINT MONO (-140 3260);
DISPLAY INVISIBLE (-140 3260);
FORCEPROP 1 LASTPIN (-150 3250) BN 18
J 0
(-162 3258);
DISPLAY 0.680851 (-162 3258);
PAINT GREEN (-162 3258);
FORCEPROP 2 LAST CDS_LIB standard
J 0
(-100 3250);
PAINT MONO (-100 3250);
DISPLAY INVISIBLE (-100 3250);
FORCEPROP 1 LAST BODY_TYPE PLUMBING
J 0
(-100 3300);
DISPLAY 0.872340 (-100 3300);
PAINT GREEN (-100 3300);
DISPLAY INVISIBLE (-100 3300);
FORCEPROP 1 LAST HDL_TAP TRUE
J 0
(225 3125);
DISPLAY 0.872340 (225 3125);
DISPLAY INVISIBLE (225 3125);
FORCEPROP 1 LAST PATH I99
J 0
(-102 3250);
DISPLAY 0.872340 (-102 3250);
PAINT GREEN (-102 3250);
DISPLAY INVISIBLE (-102 3250);
FORCEADD CAD_NOTE..1
(1750 -550);
FORCEPROP 0 LAST S1 PLACE THE BYPASS CAPS CLOSE TO DIMM
J 0
(1625 -675);
DISPLAY 1.021277 (1625 -675);
PAINT WHITE (1625 -675);
FORCEPROP 2 LAST CDS_LIB logical_power
J 0
(1750 -550);
PAINT MONO (1750 -550);
DISPLAY INVISIBLE (1750 -550);
FORCEPROP 1 LAST COMMENT_BODY TRUE
J 0
(1775 -450);
DISPLAY 0.978723 (1775 -450);
DISPLAY INVISIBLE (1775 -450);
FORCEADD QUANTA_TITLE_BLOCK_C..1
(6200 -1850);
FORCEPROP 0 LAST CDS_CON_LAST_MODIFIED Fri Aug 25 14:01:03 2023
J 0
(4315 -1835);
PAINT MONO (4315 -1835);
DISPLAY INVISIBLE (4315 -1835);
FORCEPROP 1 LAST CUSTOM_TXT_CDS <CON_LAST_MODIFIED>
J 0
(4315 -1835);
DISPLAY 0.978723 (4315 -1835);
FORCEPROP 2 LAST CUSTOM_TXT_CDS <XR_PAGE_TITLE>
J 0
(-1690 3400);
DISPLAY 0.638298 (-1690 3400);
PAINT PINK (-1690 3400);
DISPLAY INVISIBLE (-1690 3400);
FORCEPROP 2 LAST CUSTOM_TXT_CDS <NAME_2>
J 0
(3025 -1800);
FORCEPROP 2 LAST CUSTOM_TXT_CDS <NAME_1>
J 0
(3025 -1675);
FORCEPROP 2 LAST CUSTOM_TXT_CDS <Q_PROJ>
J 0
(3818 -1748);
DISPLAY 1.212766 (3818 -1748);
FORCEPROP 2 LAST CUSTOM_TXT_CDS <Q_NUMBER>
J 0
(4797 -1747);
DISPLAY 1.212766 (4797 -1747);
FORCEPROP 2 LAST CUSTOM_TXT_CDS <Q_REV>
J 0
(6016 -1747);
DISPLAY 1.212766 (6016 -1747);
FORCEPROP 2 LAST CUSTOM_TXT_CDS <CON_PAGE_NUM> OF <CON_TOTAL_PAGES>
J 0
(5754 -1832);
DISPLAY 0.978723 (5754 -1832);
FORCEPROP 1 LAST Q_TITLE DDR5 - CPU0 CHB DIMM1(YELLOW)
J 0
(-3166 -1824);
DISPLAY 2.446809 (-3166 -1824);
PAINT GREEN (-3166 -1824);
FORCEPROP 1 LAST Q_DEPT 
J 1
(2437 -1801);
DISPLAY 1.957447 (2437 -1801);
PAINT GREEN (2437 -1801);
FORCEPROP 1 LAST COMMENT_BODY TRUE
J 0
(6212 -1863);
DISPLAY 0.978723 (6212 -1863);
PAINT GREEN (6212 -1863);
DISPLAY INVISIBLE (6212 -1863);
FORCEPROP 2 LAST CDS_XR_PAGE_TITLE CR-84 : @S9S_MB_2U_LIB.S9S_MB_2U(SCH_1):PAGE84
J 0
(-1690 3400);
DISPLAY 0.638298 (-1690 3400);
PAINT PINK (-1690 3400);
DISPLAY INVISIBLE (-1690 3400);
FORCEPROP 2 LAST CDS_LIB pure_quanta
J 0
(6200 -1850);
PAINT MONO (6200 -1850);
DISPLAY INVISIBLE (6200 -1850);
FORCEPROP 1 LAST CDS_LMAN_SYM_OUTLINE -9475,6775,100,-125
J 0
(6200 -1850);
DISPLAY 0.468085 (6200 -1850);
PAINT GREEN (6200 -1850);
DISPLAY INVISIBLE (6200 -1850);
FORCEPROP 2 LAST PAGE_BORDER TRUE
J 0
(-1690 3400);
DISPLAY 0.638298 (-1690 3400);
PAINT PINK (-1690 3400);
DISPLAY INVISIBLE (-1690 3400);
WIRE 17 -1 (-50 3925)(675 3925);
FORCEPROP 2 LAST SIG_NAME M_B_CPU0_SA_DQ<31:0>
J 0
(15 3935);
DISPLAY 0.680851 (15 3935);
PAINT WHITE (15 3935);
WIRE 17 -1 (-2625 2525)(-1800 2525);
FORCEPROP 2 LAST SIG_NAME M_B_CPU0_SA_CB<7:0>
J 0
(-2535 2535);
DISPLAY 0.680851 (-2535 2535);
PAINT WHITE (-2535 2535);
WIRE 17 -1 (-1800 2225)(-1800 2275);
WIRE 17 -1 (-1800 2175)(-1800 2225);
WIRE 17 -1 (-1800 2275)(-1800 2325);
WIRE 17 -1 (-1800 2325)(-1800 2375);
WIRE 17 -1 (-1800 2375)(-1800 2425);
WIRE 17 -1 (-1800 2425)(-1800 2475);
WIRE 17 -1 (-1800 2475)(-1800 2525);
WIRE 17 -1 (-2625 2075)(-1800 2075);
FORCEPROP 2 LAST SIG_NAME M_B_CPU0_SB_CB<7:0>
J 0
(-2535 2085);
DISPLAY 0.680851 (-2535 2085);
PAINT WHITE (-2535 2085);
WIRE 17 -1 (-1800 3625)(-1800 3675);
WIRE 17 -1 (-1800 3675)(-1800 3725);
WIRE 17 -1 (-1800 3725)(-1800 3775);
WIRE 17 -1 (-1800 3775)(-1800 3825);
WIRE 17 -1 (-1800 3825)(-1800 3875);
WIRE 17 -1 (-1800 3875)(-1800 3925);
WIRE 17 -1 (-2625 3925)(-1800 3925);
FORCEPROP 2 LAST SIG_NAME M_B_CPU0_SA_CA<6:0>
J 0
(-2535 3935);
DISPLAY 0.680851 (-2535 3935);
PAINT WHITE (-2535 3935);
WIRE 17 -1 (-1800 3225)(-1800 3275);
WIRE 17 -1 (-1800 3275)(-1800 3325);
WIRE 17 -1 (-1800 3325)(-1800 3375);
WIRE 17 -1 (-1800 3375)(-1800 3425);
WIRE 17 -1 (-1800 3425)(-1800 3475);
WIRE 17 -1 (-1800 3475)(-1800 3525);
WIRE 17 -1 (-2625 3525)(-1800 3525);
FORCEPROP 2 LAST SIG_NAME M_B_CPU0_SB_CA<6:0>
J 0
(-2535 3535);
DISPLAY 0.680851 (-2535 3535);
PAINT WHITE (-2535 3535);
WIRE 17 -1 (-1800 1975)(-1800 2025);
WIRE 17 -1 (-1800 1925)(-1800 1975);
WIRE 17 -1 (-1800 2025)(-1800 2075);
WIRE 17 -1 (-1800 1775)(-1800 1825);
WIRE 17 -1 (-1800 1725)(-1800 1775);
WIRE 17 -1 (-1800 1825)(-1800 1875);
WIRE 17 -1 (-1800 1875)(-1800 1925);
WIRE 17 -1 (-50 3875)(-50 3925);
WIRE 17 -1 (-50 3825)(-50 3875);
WIRE 17 -1 (-50 3775)(-50 3825);
WIRE 17 -1 (-50 3725)(-50 3775);
WIRE 17 -1 (-50 3675)(-50 3725);
WIRE 17 -1 (-50 3625)(-50 3675);
WIRE 17 -1 (-50 3575)(-50 3625);
WIRE 17 -1 (-50 3525)(-50 3575);
WIRE 17 -1 (-50 3475)(-50 3525);
WIRE 17 -1 (-50 3425)(-50 3475);
WIRE 17 -1 (-50 3375)(-50 3425);
WIRE 17 -1 (-50 3325)(-50 3375);
WIRE 17 -1 (-50 3275)(-50 3325);
WIRE 17 -1 (-50 3225)(-50 3275);
WIRE 17 -1 (-50 3175)(-50 3225);
WIRE 17 -1 (-50 3125)(-50 3175);
WIRE 17 -1 (-50 3075)(-50 3125);
WIRE 17 -1 (-50 3025)(-50 3075);
WIRE 17 -1 (-50 2975)(-50 3025);
WIRE 17 -1 (-50 2925)(-50 2975);
WIRE 17 -1 (-50 2875)(-50 2925);
WIRE 17 -1 (-50 2825)(-50 2875);
WIRE 17 -1 (-50 2775)(-50 2825);
WIRE 17 -1 (-50 2725)(-50 2775);
WIRE 17 -1 (-50 2675)(-50 2725);
WIRE 17 -1 (-50 2625)(-50 2675);
WIRE 17 -1 (-50 2575)(-50 2625);
WIRE 17 -1 (-50 2525)(-50 2575);
WIRE 17 -1 (-50 2475)(-50 2525);
WIRE 17 -1 (-50 2425)(-50 2475);
WIRE 17 -1 (-50 2375)(-50 2425);
WIRE 17 -1 (-50 2275)(675 2275);
FORCEPROP 2 LAST SIG_NAME M_B_CPU0_SB_DQ<31:0>
J 0
(15 2285);
DISPLAY 0.680851 (15 2285);
PAINT WHITE (15 2285);
WIRE 17 -1 (-50 2225)(-50 2275);
WIRE 17 -1 (-50 2175)(-50 2225);
WIRE 17 -1 (-50 2125)(-50 2175);
WIRE 17 -1 (-50 2075)(-50 2125);
WIRE 17 -1 (-50 2025)(-50 2075);
WIRE 17 -1 (-50 1975)(-50 2025);
WIRE 17 -1 (-50 1925)(-50 1975);
WIRE 17 -1 (-50 1875)(-50 1925);
WIRE 17 -1 (-50 1825)(-50 1875);
WIRE 17 -1 (-50 1775)(-50 1825);
WIRE 17 -1 (-50 1725)(-50 1775);
WIRE 17 -1 (-50 1675)(-50 1725);
WIRE 17 -1 (-50 1625)(-50 1675);
WIRE 17 -1 (-50 1575)(-50 1625);
WIRE 17 -1 (-50 1525)(-50 1575);
WIRE 17 -1 (-50 1475)(-50 1525);
WIRE 17 -1 (-50 1425)(-50 1475);
WIRE 17 -1 (-50 1375)(-50 1425);
WIRE 17 -1 (-50 1325)(-50 1375);
WIRE 17 -1 (-50 1275)(-50 1325);
WIRE 17 -1 (-50 1225)(-50 1275);
WIRE 17 -1 (-50 1175)(-50 1225);
WIRE 17 -1 (-50 1125)(-50 1175);
WIRE 17 -1 (-50 1075)(-50 1125);
WIRE 17 -1 (-50 1025)(-50 1075);
WIRE 17 -1 (-50 975)(-50 1025);
WIRE 17 -1 (-50 925)(-50 975);
WIRE 17 -1 (-50 875)(-50 925);
WIRE 17 -1 (-50 825)(-50 875);
WIRE 17 -1 (-50 775)(-50 825);
WIRE 17 -1 (-50 725)(-50 775);
WIRE 17 -1 (2675 3825)(2675 3925);
WIRE 17 -1 (2675 3725)(2675 3825);
WIRE 17 -1 (2675 3925)(3700 3925);
FORCEPROP 2 LAST SIG_NAME M_B_CPU0_SA_DQS_DP<9:0>
J 0
(2915 3935);
DISPLAY 0.680851 (2915 3935);
PAINT WHITE (2915 3935);
WIRE 17 -1 (2675 3625)(2675 3725);
WIRE 17 -1 (2675 3525)(2675 3625);
WIRE 17 -1 (2675 3425)(2675 3525);
WIRE 17 -1 (2675 3425)(2675 3325);
WIRE 17 -1 (2675 3225)(2675 3325);
WIRE 17 -1 (2675 3125)(2675 3225);
WIRE 17 -1 (2675 3025)(2675 3125);
WIRE 17 -1 (2675 2675)(2675 2775);
WIRE 17 -1 (2675 2575)(2675 2675);
WIRE 17 -1 (2675 2775)(2675 2875);
WIRE 17 -1 (2675 2875)(3700 2875);
FORCEPROP 2 LAST SIG_NAME M_B_CPU0_SB_DQS_DP<9:0>
J 0
(2915 2885);
DISPLAY 0.680851 (2915 2885);
PAINT WHITE (2915 2885);
WIRE 17 -1 (2675 2475)(2675 2575);
WIRE 17 -1 (2675 2375)(2675 2475);
WIRE 17 -1 (2675 2375)(2675 2275);
WIRE 17 -1 (2675 2175)(2675 2275);
WIRE 17 -1 (2675 2075)(2675 2175);
WIRE 17 -1 (2675 1975)(2675 2075);
WIRE 17 -1 (2850 3775)(2850 3875);
WIRE 17 -1 (2850 3675)(2850 3775);
WIRE 17 -1 (2850 3875)(3700 3875);
FORCEPROP 2 LAST SIG_NAME M_B_CPU0_SA_DQS_DN<9:0>
J 0
(2915 3885);
DISPLAY 0.680851 (2915 3885);
PAINT WHITE (2915 3885);
WIRE 17 -1 (2850 3575)(2850 3675);
WIRE 17 -1 (2850 3475)(2850 3575);
WIRE 17 -1 (2850 3375)(2850 3475);
WIRE 17 -1 (2850 3375)(2850 3275);
WIRE 17 -1 (2850 3175)(2850 3275);
WIRE 17 -1 (2850 3075)(2850 3175);
WIRE 17 -1 (2850 2975)(2850 3075);
WIRE 17 -1 (2850 2725)(2850 2825);
WIRE 17 -1 (2850 2625)(2850 2725);
WIRE 17 -1 (2850 2825)(3700 2825);
FORCEPROP 2 LAST SIG_NAME M_B_CPU0_SB_DQS_DN<9:0>
J 0
(2915 2835);
DISPLAY 0.680851 (2915 2835);
PAINT WHITE (2915 2835);
WIRE 17 -1 (2850 2525)(2850 2625);
WIRE 17 -1 (2850 2425)(2850 2525);
WIRE 17 -1 (2850 2325)(2850 2425);
WIRE 17 -1 (2850 2325)(2850 2225);
WIRE 17 -1 (2850 2125)(2850 2225);
WIRE 17 -1 (2850 2025)(2850 2125);
WIRE 17 -1 (2850 1925)(2850 2025);
WIRE 16 -1 (-2575 1725)(-2575 1450);
WIRE 16 -1 (4325 4400)(4325 3900);
WIRE 16 -1 (2625 300)(2625 250);
WIRE 16 -1 (1625 125)(1625 300);
WIRE 16 -1 (6025 550)(6025 250);
WIRE 16 -1 (6025 600)(6025 550);
WIRE 16 -1 (5775 550)(6025 550);
WIRE 16 -1 (4325 250)(4325 650);
WIRE 16 -1 (3250 -300)(3250 -225);
WIRE 16 -1 (1625 -75)(1625 -300);
WIRE 16 -1 (-1525 -425)(-1525 -350);
WIRE 16 -1 (-325 800)(-150 800);
WIRE 16 3135 (1275 525)(1275 -775);
WIRE 16 3135 (3875 525)(1275 525);
WIRE 16 3135 (1275 -775)(3875 -775);
WIRE 16 3135 (3875 -775)(3875 525);
WIRE 16 -1 (-1700 1900)(-1525 1900);
WIRE 16 -1 (-1525 1400)(-2550 1400);
FORCEPROP 2 LAST SIG_NAME PD_CHB_CPU0_DIMM1_SAA
J 0
(-2560 1410);
DISPLAY 0.680851 (-2560 1410);
PAINT WHITE (-2560 1410);
WIRE 16 -1 (-1525 1350)(-2550 1350);
FORCEPROP 2 LAST SIG_NAME I3C_SPD_DDRABCD_CPU0_LVC1_SDA
J 0
(-2560 1360);
DISPLAY 0.680851 (-2560 1360);
PAINT WHITE (-2560 1360);
WIRE 16 -1 (-3100 1200)(-2900 1200);
WIRE 16 -1 (-3100 1300)(-3100 1200);
WIRE 16 -1 (-3100 1300)(-1525 1300);
FORCEPROP 2 LAST SIG_NAME I3C_SPD_DDRABCD_CPU0_LVC1_SCL_R3
J 0
(-2585 1310);
DISPLAY 0.680851 (-2585 1310);
PAINT WHITE (-2585 1310);
WIRE 16 -1 (-2575 1450)(-1525 1450);
WIRE 16 -1 (-1525 1550)(-2625 1550);
FORCEPROP 2 LAST SIG_NAME M_B_CPU0_ALERT_N
J 0
(-2537 1559);
DISPLAY 0.680851 (-2537 1559);
PAINT WHITE (-2537 1559);
WIRE 16 -1 (-1875 1650)(-2625 1650);
FORCEPROP 2 LAST SIG_NAME RST_M_AB_CPU0_FPGA_N
J 0
(-2537 1659);
DISPLAY 0.680851 (-2537 1659);
PAINT WHITE (-2537 1659);
WIRE 16 -1 (-1875 1650)(-1875 1600);
WIRE 16 -1 (-1875 1600)(-1525 1600);
WIRE 16 -1 (-1450 1150)(-1500 1150);
WIRE 16 -1 (-1450 1200)(-1450 1150);
WIRE 16 -1 (-2700 1200)(-1450 1200);
FORCEPROP 2 LAST SIG_NAME I3C_SPD_DDRABCD_CPU0_LVC1_SCL
J 0
(-2585 1210);
DISPLAY 0.680851 (-2585 1210);
PAINT WHITE (-2585 1210);
WIRE 16 -1 (-1700 1800)(-1525 1800);
WIRE 16 -1 (2475 3250)(2750 3250);
WIRE 16 -1 (2475 3350)(2750 3350);
WIRE 16 -1 (2475 3450)(2750 3450);
WIRE 16 -1 (2475 2200)(2750 2200);
WIRE 16 -1 (2475 2100)(2750 2100);
WIRE 16 -1 (2475 2050)(2575 2050);
WIRE 16 -1 (2475 2850)(2575 2850);
WIRE 16 -1 (2475 2950)(2750 2950);
WIRE 16 -1 (4575 3900)(4325 3900);
WIRE 16 -1 (4325 3900)(4325 3850);
WIRE 16 -1 (4325 3850)(4575 3850);
WIRE 16 -1 (4325 3850)(4325 3800);
WIRE 16 -1 (4575 3800)(4325 3800);
WIRE 16 -1 (2475 2000)(2750 2000);
WIRE 16 -1 (2475 1900)(2750 1900);
WIRE 16 -1 (2475 2300)(2750 2300);
WIRE 16 -1 (2475 2400)(2750 2400);
WIRE 16 -1 (2475 2500)(2750 2500);
WIRE 16 -1 (2475 2600)(2750 2600);
WIRE 16 -1 (2475 2700)(2750 2700);
WIRE 16 -1 (2475 2800)(2750 2800);
WIRE 16 -1 (2475 3050)(2750 3050);
WIRE 16 -1 (2475 3150)(2750 3150);
WIRE 16 -1 (2475 3550)(2750 3550);
WIRE 16 -1 (2475 3650)(2750 3650);
WIRE 16 -1 (2475 3750)(2750 3750);
WIRE 16 -1 (2750 3850)(2475 3850);
WIRE 16 -1 (2475 1950)(2575 1950);
WIRE 16 -1 (2475 2150)(2575 2150);
WIRE 16 -1 (2475 2250)(2575 2250);
WIRE 16 -1 (2475 2350)(2575 2350);
WIRE 16 -1 (2475 2450)(2575 2450);
WIRE 16 -1 (2475 2550)(2575 2550);
WIRE 16 -1 (2475 2650)(2575 2650);
WIRE 16 -1 (2475 2750)(2575 2750);
WIRE 16 -1 (2475 3000)(2575 3000);
WIRE 16 -1 (2475 3100)(2575 3100);
WIRE 16 -1 (2475 3200)(2575 3200);
WIRE 16 -1 (2475 3300)(2575 3300);
WIRE 16 -1 (2475 3400)(2575 3400);
WIRE 16 -1 (2475 3500)(2575 3500);
WIRE 16 -1 (2475 3600)(2575 3600);
WIRE 16 -1 (2475 3700)(2575 3700);
WIRE 16 -1 (2475 3800)(2575 3800);
WIRE 16 -1 (2475 3900)(2575 3900);
WIRE 16 -1 (-1525 3050)(-2625 3050);
FORCEPROP 2 LAST SIG_NAME M_B_CPU0_SB_PAR
J 0
(-2537 3059);
DISPLAY 0.680851 (-2537 3059);
PAINT WHITE (-2537 3059);
WIRE 16 -1 (-1700 1700)(-1525 1700);
WIRE 16 -1 (-1700 2000)(-1525 2000);
WIRE 16 -1 (-325 2350)(-150 2350);
WIRE 16 -1 (-1525 2750)(-2625 2750);
FORCEPROP 2 LAST SIG_NAME M_B_CPU0_SB_CS_N<0>
J 0
(-2537 2759);
DISPLAY 0.680851 (-2537 2759);
PAINT WHITE (-2537 2759);
WIRE 16 -1 (-1525 2900)(-2625 2900);
FORCEPROP 2 LAST SIG_NAME M_B_CPU0_SA_CS_N<0>
J 0
(-2537 2909);
DISPLAY 0.680851 (-2537 2909);
PAINT WHITE (-2537 2909);
WIRE 16 -1 (-1525 2950)(-2625 2950);
FORCEPROP 2 LAST SIG_NAME M_B_CPU0_SA_CS_N<1>
J 0
(-2537 2959);
DISPLAY 0.680851 (-2537 2959);
PAINT WHITE (-2537 2959);
WIRE 16 -1 (4325 650)(4575 650);
WIRE 16 -1 (4325 650)(4325 700);
WIRE 16 -1 (4325 700)(4575 700);
WIRE 16 -1 (4325 700)(4325 750);
WIRE 16 -1 (4325 750)(4575 750);
WIRE 16 -1 (4325 750)(4325 800);
WIRE 16 -1 (4325 800)(4575 800);
WIRE 16 -1 (4325 800)(4325 850);
WIRE 16 -1 (4325 850)(4575 850);
WIRE 16 -1 (4325 850)(4325 900);
WIRE 16 -1 (4325 900)(4575 900);
WIRE 16 -1 (4325 900)(4325 950);
WIRE 16 -1 (4325 950)(4575 950);
WIRE 16 -1 (4325 950)(4325 1000);
WIRE 16 -1 (4325 1000)(4575 1000);
WIRE 16 -1 (4325 1000)(4325 1050);
WIRE 16 -1 (4325 1050)(4575 1050);
WIRE 16 -1 (4325 1050)(4325 1100);
WIRE 16 -1 (4325 1100)(4575 1100);
WIRE 16 -1 (4325 1100)(4325 1150);
WIRE 16 -1 (4575 1150)(4325 1150);
WIRE 16 -1 (4325 1150)(4325 1200);
WIRE 16 -1 (4325 1200)(4575 1200);
WIRE 16 -1 (4325 1200)(4325 1250);
WIRE 16 -1 (4325 1250)(4575 1250);
WIRE 16 -1 (4325 1250)(4325 1300);
WIRE 16 -1 (4325 1300)(4575 1300);
WIRE 16 -1 (4325 1300)(4325 1350);
WIRE 16 -1 (4325 1350)(4575 1350);
WIRE 16 -1 (4325 1350)(4325 1400);
WIRE 16 -1 (4325 1400)(4575 1400);
WIRE 16 -1 (4325 1400)(4325 1450);
WIRE 16 -1 (4325 1450)(4575 1450);
WIRE 16 -1 (4325 1450)(4325 1500);
WIRE 16 -1 (4325 1500)(4575 1500);
WIRE 16 -1 (4325 1500)(4325 1550);
WIRE 16 -1 (4325 1550)(4575 1550);
WIRE 16 -1 (4325 1550)(4325 1600);
WIRE 16 -1 (4325 1600)(4575 1600);
WIRE 16 -1 (4325 1600)(4325 1650);
WIRE 16 -1 (4575 1650)(4325 1650);
WIRE 16 -1 (4325 1650)(4325 1700);
WIRE 16 -1 (4325 1700)(4575 1700);
WIRE 16 -1 (4325 1700)(4325 1750);
WIRE 16 -1 (4325 1750)(4575 1750);
WIRE 16 -1 (4325 1750)(4325 1800);
WIRE 16 -1 (4325 1800)(4575 1800);
WIRE 16 -1 (4325 1800)(4325 1850);
WIRE 16 -1 (4325 1850)(4575 1850);
WIRE 16 -1 (4325 1850)(4325 1900);
WIRE 16 -1 (4325 1900)(4575 1900);
WIRE 16 -1 (4325 1900)(4325 1950);
WIRE 16 -1 (4325 1950)(4575 1950);
WIRE 16 -1 (4325 1950)(4325 2000);
WIRE 16 -1 (4325 2000)(4575 2000);
WIRE 16 -1 (4325 2000)(4325 2050);
WIRE 16 -1 (4325 2050)(4575 2050);
WIRE 16 -1 (4325 2050)(4325 2100);
WIRE 16 -1 (4325 2100)(4575 2100);
WIRE 16 -1 (4325 2100)(4325 2150);
WIRE 16 -1 (4575 2150)(4325 2150);
WIRE 16 -1 (4325 2150)(4325 2200);
WIRE 16 -1 (4325 2200)(4575 2200);
WIRE 16 -1 (4325 2200)(4325 2250);
WIRE 16 -1 (4325 2250)(4575 2250);
WIRE 16 -1 (4325 2250)(4325 2300);
WIRE 16 -1 (4325 2300)(4575 2300);
WIRE 16 -1 (4325 2300)(4325 2350);
WIRE 16 -1 (4325 2350)(4575 2350);
WIRE 16 -1 (4325 2350)(4325 2400);
WIRE 16 -1 (4325 2400)(4575 2400);
WIRE 16 -1 (4325 2400)(4325 2450);
WIRE 16 -1 (4325 2450)(4575 2450);
WIRE 16 -1 (4325 2450)(4325 2500);
WIRE 16 -1 (4325 2500)(4575 2500);
WIRE 16 -1 (4325 2500)(4325 2550);
WIRE 16 -1 (4325 2550)(4575 2550);
WIRE 16 -1 (4325 2550)(4325 2600);
WIRE 16 -1 (4325 2600)(4575 2600);
WIRE 16 -1 (4325 2600)(4325 2650);
WIRE 16 -1 (4575 2650)(4325 2650);
WIRE 16 -1 (4325 2650)(4325 2700);
WIRE 16 -1 (4325 2700)(4575 2700);
WIRE 16 -1 (4325 2700)(4325 2750);
WIRE 16 -1 (4325 2750)(4575 2750);
WIRE 16 -1 (4325 2750)(4325 2800);
WIRE 16 -1 (4325 2800)(4575 2800);
WIRE 16 -1 (4325 2800)(4325 2850);
WIRE 16 -1 (4325 2850)(4575 2850);
WIRE 16 -1 (4325 2850)(4325 2900);
WIRE 16 -1 (4325 2900)(4575 2900);
WIRE 16 -1 (4325 2900)(4325 2950);
WIRE 16 -1 (4325 2950)(4575 2950);
WIRE 16 -1 (4325 2950)(4325 3000);
WIRE 16 -1 (4325 3000)(4575 3000);
WIRE 16 -1 (4325 3000)(4325 3050);
WIRE 16 -1 (4325 3050)(4575 3050);
WIRE 16 -1 (4325 3050)(4325 3100);
WIRE 16 -1 (4325 3100)(4575 3100);
WIRE 16 -1 (4325 3100)(4325 3150);
WIRE 16 -1 (4575 3150)(4325 3150);
WIRE 16 -1 (4325 3150)(4325 3200);
WIRE 16 -1 (4325 3200)(4575 3200);
WIRE 16 -1 (4325 3200)(4325 3250);
WIRE 16 -1 (4325 3250)(4575 3250);
WIRE 16 -1 (4325 3250)(4325 3300);
WIRE 16 -1 (4325 3300)(4575 3300);
WIRE 16 -1 (4325 3300)(4325 3350);
WIRE 16 -1 (4325 3350)(4575 3350);
WIRE 16 -1 (4325 3350)(4325 3400);
WIRE 16 -1 (4325 3400)(4575 3400);
WIRE 16 -1 (4325 3400)(4325 3450);
WIRE 16 -1 (4325 3450)(4575 3450);
WIRE 16 -1 (4325 3450)(4325 3500);
WIRE 16 -1 (4325 3500)(4575 3500);
WIRE 16 -1 (4325 3500)(4325 3550);
WIRE 16 -1 (4325 3550)(4575 3550);
WIRE 16 -1 (4325 3550)(4325 3600);
WIRE 16 -1 (4325 3600)(4575 3600);
WIRE 16 -1 (4325 3600)(4325 3650);
WIRE 16 -1 (4575 3650)(4325 3650);
WIRE 16 -1 (4325 3650)(4325 3700);
WIRE 16 -1 (4325 3700)(4575 3700);
WIRE 16 -1 (4325 3700)(4325 3750);
WIRE 16 -1 (4575 3750)(4325 3750);
WIRE 16 -1 (-325 2500)(-150 2500);
WIRE 16 -1 (-325 2450)(-150 2450);
WIRE 16 -1 (-1700 2350)(-1525 2350);
WIRE 16 -1 (-1700 1850)(-1525 1850);
WIRE 16 -1 (-1525 2600)(-2625 2600);
FORCEPROP 2 LAST SIG_NAME M_B_CPU0_CLK_DN<0>
J 0
(-2537 2609);
DISPLAY 0.680851 (-2537 2609);
PAINT WHITE (-2537 2609);
WIRE 16 -1 (-1525 2650)(-2625 2650);
FORCEPROP 2 LAST SIG_NAME M_B_CPU0_CLK_DP<0>
J 0
(-2537 2659);
DISPLAY 0.680851 (-2537 2659);
PAINT WHITE (-2537 2659);
WIRE 16 -1 (-325 2700)(-150 2700);
WIRE 16 -1 (-1525 650)(-2625 650);
FORCEPROP 2 LAST SIG_NAME TP_CHB_CPU0_DIMM1_FRU_0
J 0
(-2537 659);
DISPLAY 0.680851 (-2537 659);
PAINT WHITE (-2537 659);
WIRE 16 -1 (-1525 700)(-2625 700);
FORCEPROP 2 LAST SIG_NAME TP_CHB_CPU0_DIMM1_FRU_1
J 0
(-2537 709);
DISPLAY 0.680851 (-2537 709);
PAINT WHITE (-2537 709);
WIRE 16 -1 (-1525 750)(-2625 750);
FORCEPROP 2 LAST SIG_NAME TP_CHB_CPU0_DIMM1_FRU_2
J 0
(-2537 759);
DISPLAY 0.680851 (-2537 759);
PAINT WHITE (-2537 759);
WIRE 16 -1 (-1525 800)(-2625 800);
FORCEPROP 2 LAST SIG_NAME TP_CHB_CPU0_DIMM1_FRU_3
J 0
(-2537 809);
DISPLAY 0.680851 (-2537 809);
PAINT WHITE (-2537 809);
WIRE 16 -1 (-1525 850)(-2625 850);
FORCEPROP 2 LAST SIG_NAME TP_CHB_CPU0_DIMM1_FRU_4
J 0
(-2537 859);
DISPLAY 0.680851 (-2537 859);
PAINT WHITE (-2537 859);
WIRE 16 -1 (-1525 900)(-2625 900);
FORCEPROP 2 LAST SIG_NAME TP_CHB_CPU0_DIMM1_FRU_5
J 0
(-2537 909);
DISPLAY 0.680851 (-2537 909);
PAINT WHITE (-2537 909);
WIRE 16 -1 (-1525 950)(-2625 950);
FORCEPROP 2 LAST SIG_NAME TP_CHB_CPU0_DIMM1_FRU_6
J 0
(-2537 959);
DISPLAY 0.680851 (-2537 959);
PAINT WHITE (-2537 959);
WIRE 16 -1 (-1525 1050)(-2625 1050);
FORCEPROP 2 LAST SIG_NAME PWRGD_CHB_CPU0_DIMM1
J 0
(-2537 1059);
DISPLAY 0.680851 (-2537 1059);
PAINT WHITE (-2537 1059);
WIRE 16 -1 (-1525 3100)(-2625 3100);
FORCEPROP 2 LAST SIG_NAME M_B_CPU0_SA_PAR
J 0
(-2537 3109);
DISPLAY 0.680851 (-2537 3109);
PAINT WHITE (-2537 3109);
WIRE 16 -1 (-1525 450)(-2625 450);
FORCEPROP 2 LAST SIG_NAME M_B_CPU0_SB_RSP<0>
J 0
(-2537 459);
DISPLAY 0.680851 (-2537 459);
PAINT WHITE (-2537 459);
WIRE 16 -1 (-1525 500)(-2625 500);
FORCEPROP 2 LAST SIG_NAME M_B_CPU0_SA_RSP<0>
J 0
(-2537 509);
DISPLAY 0.680851 (-2537 509);
PAINT WHITE (-2537 509);
WIRE 16 -1 (-325 700)(-150 700);
WIRE 16 -1 (-325 750)(-150 750);
WIRE 16 -1 (-325 850)(-150 850);
WIRE 16 -1 (-325 900)(-150 900);
WIRE 16 -1 (-325 950)(-150 950);
WIRE 16 -1 (-325 1000)(-150 1000);
WIRE 16 -1 (-325 1050)(-150 1050);
WIRE 16 -1 (-325 1100)(-150 1100);
WIRE 16 -1 (-325 1150)(-150 1150);
WIRE 16 -1 (-325 1200)(-150 1200);
WIRE 16 -1 (-325 1250)(-150 1250);
WIRE 16 -1 (-325 1300)(-150 1300);
WIRE 16 -1 (-325 1350)(-150 1350);
WIRE 16 -1 (-325 1400)(-150 1400);
WIRE 16 -1 (-325 1450)(-150 1450);
WIRE 16 -1 (-325 1500)(-150 1500);
WIRE 16 -1 (-325 1550)(-150 1550);
WIRE 16 -1 (-325 1600)(-150 1600);
WIRE 16 -1 (-325 1650)(-150 1650);
WIRE 16 -1 (-325 1700)(-150 1700);
WIRE 16 -1 (-325 1750)(-150 1750);
WIRE 16 -1 (-325 1800)(-150 1800);
WIRE 16 -1 (-325 1850)(-150 1850);
WIRE 16 -1 (-325 1900)(-150 1900);
WIRE 16 -1 (-325 1950)(-150 1950);
WIRE 16 -1 (-325 2000)(-150 2000);
WIRE 16 -1 (-325 2050)(-150 2050);
WIRE 16 -1 (-325 2100)(-150 2100);
WIRE 16 -1 (-325 2150)(-150 2150);
WIRE 16 -1 (-325 2200)(-150 2200);
WIRE 16 -1 (-325 2250)(-150 2250);
WIRE 16 -1 (-325 2400)(-150 2400);
WIRE 16 -1 (-325 2550)(-150 2550);
WIRE 16 -1 (-325 2600)(-150 2600);
WIRE 16 -1 (-325 2650)(-150 2650);
WIRE 16 -1 (-325 2750)(-150 2750);
WIRE 16 -1 (-325 2800)(-150 2800);
WIRE 16 -1 (-325 2850)(-150 2850);
WIRE 16 -1 (-325 2900)(-150 2900);
WIRE 16 -1 (-325 2950)(-150 2950);
WIRE 16 -1 (-325 3000)(-150 3000);
WIRE 16 -1 (-325 3050)(-150 3050);
WIRE 16 -1 (-325 3100)(-150 3100);
WIRE 16 -1 (-325 3150)(-150 3150);
WIRE 16 -1 (-325 3200)(-150 3200);
WIRE 16 -1 (-325 3250)(-150 3250);
WIRE 16 -1 (-325 3300)(-150 3300);
WIRE 16 -1 (-325 3350)(-150 3350);
WIRE 16 -1 (-325 3400)(-150 3400);
WIRE 16 -1 (-325 3450)(-150 3450);
WIRE 16 -1 (-325 3500)(-150 3500);
WIRE 16 -1 (-325 3550)(-150 3550);
WIRE 16 -1 (-325 3600)(-150 3600);
WIRE 16 -1 (-325 3650)(-150 3650);
WIRE 16 -1 (-325 3700)(-150 3700);
WIRE 16 -1 (-325 3750)(-150 3750);
WIRE 16 -1 (-325 3800)(-150 3800);
WIRE 16 -1 (-325 3850)(-150 3850);
WIRE 16 -1 (-1525 2800)(-2625 2800);
FORCEPROP 2 LAST SIG_NAME M_B_CPU0_SB_CS_N<1>
J 0
(-2537 2809);
DISPLAY 0.680851 (-2537 2809);
PAINT WHITE (-2537 2809);
WIRE 16 -1 (-1700 1750)(-1525 1750);
WIRE 16 -1 (-1700 1950)(-1525 1950);
WIRE 16 -1 (-1700 2150)(-1525 2150);
WIRE 16 -1 (-1700 2250)(-1525 2250);
WIRE 16 -1 (-1700 2300)(-1525 2300);
WIRE 16 -1 (-1700 2400)(-1525 2400);
WIRE 16 -1 (-1700 2450)(-1525 2450);
WIRE 16 -1 (-1700 3500)(-1525 3500);
WIRE 16 -1 (-1700 3900)(-1525 3900);
WIRE 16 -1 (-1700 3450)(-1525 3450);
WIRE 16 -1 (-1700 3850)(-1525 3850);
WIRE 16 -1 (-1700 3400)(-1525 3400);
WIRE 16 -1 (-1700 3800)(-1525 3800);
WIRE 16 -1 (-1700 3350)(-1525 3350);
WIRE 16 -1 (-1700 3750)(-1525 3750);
WIRE 16 -1 (-1700 3300)(-1525 3300);
WIRE 16 -1 (-1700 3700)(-1525 3700);
WIRE 16 -1 (-1700 3250)(-1525 3250);
WIRE 16 -1 (-1700 3650)(-1525 3650);
WIRE 16 -1 (-1700 3200)(-1525 3200);
WIRE 16 -1 (-1700 3600)(-1525 3600);
WIRE 16 -1 (-1700 2050)(-1525 2050);
WIRE 16 -1 (-1700 2200)(-1525 2200);
WIRE 16 -1 (-1700 2500)(-1525 2500);
WIRE 16 -1 (-325 3900)(-150 3900);
WIRE 16 -1 (5775 3900)(6025 3900);
WIRE 16 -1 (5775 3850)(6025 3850);
WIRE 16 -1 (6025 3900)(6025 3850);
WIRE 16 -1 (5775 3800)(6025 3800);
WIRE 16 -1 (6025 3850)(6025 3800);
WIRE 16 -1 (5775 3750)(6025 3750);
WIRE 16 -1 (6025 3800)(6025 3750);
WIRE 16 -1 (5775 3700)(6025 3700);
WIRE 16 -1 (6025 3750)(6025 3700);
WIRE 16 -1 (5775 3650)(6025 3650);
WIRE 16 -1 (6025 3700)(6025 3650);
WIRE 16 -1 (5775 3600)(6025 3600);
WIRE 16 -1 (6025 3650)(6025 3600);
WIRE 16 -1 (5775 3550)(6025 3550);
WIRE 16 -1 (6025 3600)(6025 3550);
WIRE 16 -1 (5775 3500)(6025 3500);
WIRE 16 -1 (6025 3550)(6025 3500);
WIRE 16 -1 (5775 3450)(6025 3450);
WIRE 16 -1 (6025 3500)(6025 3450);
WIRE 16 -1 (5775 3400)(6025 3400);
WIRE 16 -1 (6025 3450)(6025 3400);
WIRE 16 -1 (5775 3350)(6025 3350);
WIRE 16 -1 (6025 3400)(6025 3350);
WIRE 16 -1 (5775 3300)(6025 3300);
WIRE 16 -1 (6025 3350)(6025 3300);
WIRE 16 -1 (5775 3250)(6025 3250);
WIRE 16 -1 (6025 3300)(6025 3250);
WIRE 16 -1 (5775 3200)(6025 3200);
WIRE 16 -1 (6025 3250)(6025 3200);
WIRE 16 -1 (5775 3150)(6025 3150);
WIRE 16 -1 (6025 3150)(6025 3200);
WIRE 16 -1 (5775 3100)(6025 3100);
WIRE 16 -1 (6025 3150)(6025 3100);
WIRE 16 -1 (6025 3050)(5775 3050);
WIRE 16 -1 (6025 3100)(6025 3050);
WIRE 16 -1 (6025 3000)(5775 3000);
WIRE 16 -1 (6025 3050)(6025 3000);
WIRE 16 -1 (5775 2950)(6025 2950);
WIRE 16 -1 (6025 3000)(6025 2950);
WIRE 16 -1 (5775 2900)(6025 2900);
WIRE 16 -1 (6025 2950)(6025 2900);
WIRE 16 -1 (5775 2850)(6025 2850);
WIRE 16 -1 (6025 2900)(6025 2850);
WIRE 16 -1 (5775 2800)(6025 2800);
WIRE 16 -1 (6025 2850)(6025 2800);
WIRE 16 -1 (5775 2750)(6025 2750);
WIRE 16 -1 (6025 2800)(6025 2750);
WIRE 16 -1 (5775 2700)(6025 2700);
WIRE 16 -1 (6025 2750)(6025 2700);
WIRE 16 -1 (5775 2650)(6025 2650);
WIRE 16 -1 (6025 2650)(6025 2700);
WIRE 16 -1 (5775 2600)(6025 2600);
WIRE 16 -1 (6025 2650)(6025 2600);
WIRE 16 -1 (6025 2550)(5775 2550);
WIRE 16 -1 (6025 2600)(6025 2550);
WIRE 16 -1 (6025 2500)(5775 2500);
WIRE 16 -1 (6025 2550)(6025 2500);
WIRE 16 -1 (5775 2450)(6025 2450);
WIRE 16 -1 (6025 2500)(6025 2450);
WIRE 16 -1 (5775 2400)(6025 2400);
WIRE 16 -1 (6025 2450)(6025 2400);
WIRE 16 -1 (5775 2350)(6025 2350);
WIRE 16 -1 (6025 2400)(6025 2350);
WIRE 16 -1 (5775 2300)(6025 2300);
WIRE 16 -1 (6025 2350)(6025 2300);
WIRE 16 -1 (5775 2250)(6025 2250);
WIRE 16 -1 (6025 2300)(6025 2250);
WIRE 16 -1 (5775 2200)(6025 2200);
WIRE 16 -1 (6025 2250)(6025 2200);
WIRE 16 -1 (5775 2150)(6025 2150);
WIRE 16 -1 (6025 2150)(6025 2200);
WIRE 16 -1 (5775 2100)(6025 2100);
WIRE 16 -1 (6025 2150)(6025 2100);
WIRE 16 -1 (6025 2050)(5775 2050);
WIRE 16 -1 (6025 2100)(6025 2050);
WIRE 16 -1 (6025 2000)(5775 2000);
WIRE 16 -1 (6025 2050)(6025 2000);
WIRE 16 -1 (5775 1950)(6025 1950);
WIRE 16 -1 (6025 2000)(6025 1950);
WIRE 16 -1 (5775 1900)(6025 1900);
WIRE 16 -1 (6025 1950)(6025 1900);
WIRE 16 -1 (5775 1850)(6025 1850);
WIRE 16 -1 (6025 1900)(6025 1850);
WIRE 16 -1 (5775 1800)(6025 1800);
WIRE 16 -1 (6025 1850)(6025 1800);
WIRE 16 -1 (5775 1750)(6025 1750);
WIRE 16 -1 (6025 1800)(6025 1750);
WIRE 16 -1 (5775 1700)(6025 1700);
WIRE 16 -1 (6025 1750)(6025 1700);
WIRE 16 -1 (5775 1650)(6025 1650);
WIRE 16 -1 (6025 1650)(6025 1700);
WIRE 16 -1 (5775 1600)(6025 1600);
WIRE 16 -1 (6025 1650)(6025 1600);
WIRE 16 -1 (6025 1550)(5775 1550);
WIRE 16 -1 (6025 1600)(6025 1550);
WIRE 16 -1 (6025 1500)(5775 1500);
WIRE 16 -1 (6025 1550)(6025 1500);
WIRE 16 -1 (6025 1450)(5775 1450);
WIRE 16 -1 (6025 1500)(6025 1450);
WIRE 16 -1 (6025 1400)(5775 1400);
WIRE 16 -1 (6025 1450)(6025 1400);
WIRE 16 -1 (5775 1350)(6025 1350);
WIRE 16 -1 (6025 1350)(6025 1400);
WIRE 16 -1 (6025 1300)(5775 1300);
WIRE 16 -1 (6025 1300)(6025 1350);
WIRE 16 -1 (6025 1250)(5775 1250);
WIRE 16 -1 (6025 1300)(6025 1250);
WIRE 16 -1 (6025 1200)(5775 1200);
WIRE 16 -1 (6025 1250)(6025 1200);
WIRE 16 -1 (5775 1150)(6025 1150);
WIRE 16 -1 (6025 1200)(6025 1150);
WIRE 16 -1 (5775 1100)(6025 1100);
WIRE 16 -1 (6025 1150)(6025 1100);
WIRE 16 -1 (5775 1050)(6025 1050);
WIRE 16 -1 (6025 1100)(6025 1050);
WIRE 16 -1 (5775 1000)(6025 1000);
WIRE 16 -1 (6025 1050)(6025 1000);
WIRE 16 -1 (5775 950)(6025 950);
WIRE 16 -1 (6025 1000)(6025 950);
WIRE 16 -1 (5775 900)(6025 900);
WIRE 16 -1 (6025 950)(6025 900);
WIRE 16 -1 (5775 850)(6025 850);
WIRE 16 -1 (6025 900)(6025 850);
WIRE 16 -1 (5775 800)(6025 800);
WIRE 16 -1 (6025 800)(6025 850);
WIRE 16 -1 (5775 750)(6025 750);
WIRE 16 -1 (6025 800)(6025 750);
WIRE 16 -1 (5775 650)(6025 650);
WIRE 16 -1 (6025 750)(6025 650);
WIRE 16 -1 (6025 650)(6025 600);
WIRE 16 -1 (5775 600)(6025 600);
WIRE 16 -1 (-1525 -50)(-2625 -50);
FORCEPROP 2 LAST SIG_NAME PD_CHB_CPU0_DIMM1_SAA
J 0
(-2537 -41);
DISPLAY 0.680851 (-2537 -41);
PAINT WHITE (-2537 -41);
WIRE 16 -1 (-1525 -150)(-1525 -50);
WIRE 16 -1 (2625 250)(2625 125);
WIRE 16 -1 (3250 250)(2625 250);
WIRE 16 -1 (3250 125)(3250 250);
WIRE 16 -1 (2625 -225)(2625 -75);
WIRE 16 -1 (3250 -225)(2625 -225);
WIRE 16 -1 (3250 -225)(3250 -75);
DOT 1 (4325 2500);
DOT 1 (6025 550);
DOT 1 (6025 600);
DOT 1 (6025 650);
DOT 1 (6025 3850);
DOT 1 (6025 3800);
DOT 1 (6025 3600);
DOT 1 (6025 3650);
DOT 1 (6025 3700);
DOT 1 (6025 3750);
DOT 1 (6025 3550);
DOT 1 (6025 3400);
DOT 1 (6025 3350);
DOT 1 (6025 3450);
DOT 1 (6025 3500);
DOT 1 (6025 3300);
DOT 1 (6025 3150);
DOT 1 (6025 3100);
DOT 1 (6025 3200);
DOT 1 (6025 3250);
DOT 1 (6025 3050);
DOT 1 (6025 2900);
DOT 1 (6025 2850);
DOT 1 (6025 2950);
DOT 1 (6025 3000);
DOT 1 (6025 2700);
DOT 1 (6025 2650);
DOT 1 (6025 2600);
DOT 1 (6025 2800);
DOT 1 (6025 2750);
DOT 1 (6025 2550);
DOT 1 (6025 2350);
DOT 1 (6025 2400);
DOT 1 (6025 2500);
DOT 1 (6025 2450);
DOT 1 (6025 2300);
DOT 1 (6025 2200);
DOT 1 (6025 2100);
DOT 1 (6025 2150);
DOT 1 (6025 2250);
DOT 1 (4325 3900);
DOT 1 (4325 3850);
DOT 1 (4325 3700);
DOT 1 (4325 3650);
DOT 1 (4325 3600);
DOT 1 (4325 3550);
DOT 1 (4325 3500);
DOT 1 (4325 3450);
DOT 1 (4325 3400);
DOT 1 (4325 3350);
DOT 1 (4325 3300);
DOT 1 (4325 3250);
DOT 1 (4325 3200);
DOT 1 (4325 3150);
DOT 1 (4325 3100);
DOT 1 (4325 3050);
DOT 1 (4325 3000);
DOT 1 (4325 2900);
DOT 1 (4325 2850);
DOT 1 (4325 2800);
DOT 1 (4325 2750);
DOT 1 (4325 2700);
DOT 1 (4325 2650);
DOT 1 (4325 2600);
DOT 1 (4325 2550);
DOT 1 (4325 2450);
DOT 1 (4325 2400);
DOT 1 (4325 2350);
DOT 1 (4325 2300);
DOT 1 (4325 2250);
DOT 1 (4325 2200);
DOT 1 (4325 2150);
DOT 1 (4325 2100);
DOT 1 (6025 2050);
DOT 1 (4325 2050);
DOT 1 (6025 1950);
DOT 1 (6025 1850);
DOT 1 (6025 1900);
DOT 1 (6025 2000);
DOT 1 (6025 1800);
DOT 1 (6025 1750);
DOT 1 (6025 1550);
DOT 1 (6025 1600);
DOT 1 (6025 1650);
DOT 1 (6025 1700);
DOT 1 (6025 1500);
DOT 1 (6025 1350);
DOT 1 (6025 1300);
DOT 1 (6025 1400);
DOT 1 (6025 1450);
DOT 1 (6025 1250);
DOT 1 (6025 1100);
DOT 1 (6025 1050);
DOT 1 (6025 1200);
DOT 1 (6025 1150);
DOT 1 (6025 850);
DOT 1 (6025 800);
DOT 1 (6025 900);
DOT 1 (6025 950);
DOT 1 (6025 750);
DOT 1 (4325 1950);
DOT 1 (4325 2000);
DOT 1 (4325 1900);
DOT 1 (4325 1850);
DOT 1 (4325 1800);
DOT 1 (4325 1700);
DOT 1 (4325 1750);
DOT 1 (4325 1650);
DOT 1 (4325 1550);
DOT 1 (4325 1600);
DOT 1 (4325 1500);
DOT 1 (4325 1450);
DOT 1 (4325 1400);
DOT 1 (4325 1350);
DOT 1 (4325 1300);
DOT 1 (4325 1200);
DOT 1 (4325 1250);
DOT 1 (4325 1150);
DOT 1 (4325 1050);
DOT 1 (4325 1000);
DOT 1 (4325 900);
DOT 1 (4325 850);
DOT 1 (4325 800);
DOT 1 (4325 750);
DOT 1 (4325 700);
DOT 1 (4325 650);
DOT 1 (2625 250);
DOT 1 (3250 -225);
DOT 1 (6025 1000);
DOT 1 (4325 950);
DOT 1 (4325 1100);
DOT 1 (4325 2950);
FORCENOTE
20210728 MODIFY FOR GT
(-2975 4575) 0;
DISPLAY LEFT (-2975 4575);
DISPLAY 2.510638 (-2975 4575);
PAINT PINK (-2975 4575);
QUIT
